G04 ================== begin FILE IDENTIFICATION RECORD ==================*
G04 Layout Name:  DA0T6MTH8C0_t6m_tray_bp_c_brd_103112_274.brd*
G04 Film Name:    vcc*
G04 File Format:  Gerber RS274X*
G04 File Origin:  Cadence Allegro 16.3-S048*
G04 Origin Date:  Tue Nov 26 11:26:41 2013*
G04 *
G04 Layer:  DRAWING FORMAT/TITLE_BLOCK*
G04 Layer:  VIA CLASS/VCC*
G04 Layer:  PIN/VCC*
G04 Layer:  MANUFACTURING/PHOTOPLOT_OUTLINE*
G04 Layer:  ETCH/VCC*
G04 Layer:  DRAWING FORMAT/TITLE_DATA_VCC*
G04 *
G04 Offset:    (0.00 0.00)*
G04 Mirror:    No*
G04 Mode:      Negative*
G04 Rotation:  0*
G04 FullContactRelief:  No*
G04 UndefLineWidth:     6.00*
G04 ================== end FILE IDENTIFICATION RECORD ====================*
%FSLAX25Y25*MOIN*%
%IR0*IPPOS*OFA0.00000B0.00000*MIA0B0*SFA1.00000B1.00000*%
%ADD21C,.03*%
%ADD22C,.04*%
%ADD24C,.05*%
%ADD10C,.042*%
%ADD29C,.061*%
%ADD31C,.053*%
%ADD19C,.072*%
%ADD16C,.063*%
%ADD36C,.082*%
%ADD32C,.055*%
%ADD14C,.073*%
%ADD28C,.093*%
%ADD27C,.057*%
%ADD11C,.066*%
%ADD20C,.058*%
%AMMACRO17*
4,1,36,0.0,.009,
.001563,.008863,
.003078,.008457,
.0045,.007794,
.005785,.006894,
.006894,.005785,
.007794,.0045,
.008457,.003078,
.008863,.001563,
.009,0.0,
.008863,-.001563,
.008457,-.003078,
.007794,-.0045,
.006894,-.005785,
.005785,-.006894,
.0045,-.007794,
.003078,-.008457,
.001563,-.008863,
0.0,-.009,
-.001563,-.008863,
-.003078,-.008457,
-.0045,-.007794,
-.005785,-.006894,
-.006894,-.005785,
-.007794,-.0045,
-.008457,-.003078,
-.008863,-.001563,
-.009,0.0,
-.008863,.001563,
-.008457,.003078,
-.007794,.0045,
-.006894,.005785,
-.005785,.006894,
-.0045,.007794,
-.003078,.008457,
-.001563,.008863,
0.0,.009,
0.0*
%
%ADD17MACRO17*%
%AMMACRO26*
4,1,36,0.0,.014,
-.002431,.013787,
-.004788,.013156,
-.007,.012124,
-.008999,.010725,
-.010725,.008999,
-.012124,.007,
-.013156,.004788,
-.013787,.002431,
-.014,0.0,
-.013787,-.002431,
-.013156,-.004788,
-.012124,-.007,
-.010725,-.008999,
-.008999,-.010725,
-.007,-.012124,
-.004788,-.013156,
-.002431,-.013787,
0.0,-.014,
.002431,-.013787,
.004788,-.013156,
.007,-.012124,
.008999,-.010725,
.010725,-.008999,
.012124,-.007,
.013156,-.004788,
.013787,-.002431,
.014,0.0,
.013787,.002431,
.013156,.004788,
.012124,.007,
.010725,.008999,
.008999,.010725,
.007,.012124,
.004788,.013156,
.002431,.013787,
0.0,.014,
0.0*
%
%ADD26MACRO26*%
%AMMACRO15*
4,1,16,.02548,.01487,
.027675,.01022,
.029029,.005259,
.029501,.000138,
.029077,-.004987,
.027769,-.009961,
.025618,-.014631,
.02548,-.01487,
.03056,-.01996,
.033562,-.01435,
.035544,-.008304,
.036446,-.002006,
.03624,.004353,
.034934,.01058,
.032566,.016486,
.03056,.01996,
.02548,.01487,
90.*
4,1,16,.01487,-.02548,
.01022,-.027675,
.005259,-.029029,
.000138,-.029501,
-.004987,-.029077,
-.009961,-.027769,
-.014631,-.025618,
-.01487,-.02548,
-.01996,-.03056,
-.01435,-.033562,
-.008304,-.035544,
-.002006,-.036446,
.004353,-.03624,
.01058,-.034934,
.016486,-.032566,
.01996,-.03056,
.01487,-.02548,
90.*
4,1,16,-.02548,-.01487,
-.027675,-.01022,
-.029029,-.005259,
-.029501,-.000138,
-.029077,.004987,
-.027769,.009961,
-.025618,.014631,
-.02548,.01487,
-.03056,.01996,
-.033562,.01435,
-.035544,.008304,
-.036446,.002006,
-.03624,-.004353,
-.034934,-.01058,
-.032566,-.016486,
-.03056,-.01996,
-.02548,-.01487,
90.*
4,1,16,-.01487,.02548,
-.01022,.027675,
-.005259,.029029,
-.000138,.029501,
.004987,.029077,
.009961,.027769,
.014631,.025618,
.01487,.02548,
.01996,.03056,
.01435,.033562,
.008304,.035544,
.002006,.036446,
-.004353,.03624,
-.01058,.034934,
-.016486,.032566,
-.01996,.03056,
-.01487,.02548,
90.*
%
%ADD15MACRO15*%
%ADD33C,.1*%
%ADD25C,.115*%
%ADD12C,.172*%
%ADD35C,.119*%
%ADD34C,.158*%
%ADD30O,.068X.093*%
%ADD13C,.168*%
%ADD23C,.178*%
%AMMACRO18*
4,1,36,0.0,.004,
.000695,.003939,
.001368,.003759,
.002,.003464,
.002571,.003064,
.003064,.002571,
.003464,.002,
.003759,.001368,
.003939,.000695,
.004,0.0,
.003939,-.000695,
.003759,-.001368,
.003464,-.002,
.003064,-.002571,
.002571,-.003064,
.002,-.003464,
.001368,-.003759,
.000695,-.003939,
0.0,-.004,
-.000695,-.003939,
-.001368,-.003759,
-.002,-.003464,
-.002571,-.003064,
-.003064,-.002571,
-.003464,-.002,
-.003759,-.001368,
-.003939,-.000695,
-.004,0.0,
-.003939,.000695,
-.003759,.001368,
-.003464,.002,
-.003064,.002571,
-.002571,.003064,
-.002,.003464,
-.001368,.003759,
-.000695,.003939,
0.0,.004,
0.0*
%
%ADD18MACRO18*%
%ADD37C,.006*%
%ADD39R,.057X.111*%
%ADD38R,.051X.109*%
%ADD40R,.051X.11294*%
%ADD42C,.09612*%
%ADD48C,.07608*%
%ADD43C,.09606*%
%ADD44C,.1601*%
%ADD45C,.16024*%
%ADD46C,.11706*%
%ADD41R,.072X.096*%
%ADD47C,.11708*%
G75*
%LPD*%
G75*
G36*
G01X-471400Y-391900D02*
X2244200D01*
Y1528800D01*
X-471400D01*
Y-391900D01*
G37*
%LPC*%
G75*
G36*
G01X28200Y4000D02*
G02X27700Y4500I0J500D01*
G01Y5384D01*
X27800Y5590D01*
X27890Y5661D01*
G03X5285Y29174I-10173J12843D01*
G01X5214Y29091D01*
X5016Y29000D01*
X4500D01*
G02X4000Y29500I0J500D01*
G01Y126800D01*
G02X5757Y127454I1000J0D01*
G03X6606Y126546I11964J10336D01*
G01X6676Y126476D01*
X6827Y126119D01*
Y114367D01*
G03Y113977I10889J-195D01*
G01Y113334D01*
X6858Y113303D01*
X6876Y113124D01*
Y113123D01*
G03X28606Y114173I10840J1050D01*
G01Y126119D01*
X28757Y126476D01*
X28827Y126546D01*
G03X5756Y148135I-11111J11249D01*
G02X4000Y148789I-756J654D01*
G01Y182700D01*
G02X4500Y183200I500J0D01*
G01X36642D01*
G02X37142Y182700I0J-500D01*
G01Y167916D01*
G03X47898I5378J0D01*
G01Y177600D01*
G02X48398Y178100I500J0D01*
G01X200539D01*
G02X201039Y177600I0J-500D01*
G01Y170551D01*
G03X208976Y162614I7937J0D01*
G01X216850D01*
G03X224787Y170551I0J7937D01*
G01Y198110D01*
G02X228661Y201984I3874J0D01*
G01X304870D01*
G02X305426Y200153I0J-1000D01*
G03X303102Y175760I8786J-13144D01*
G01X303172Y175690D01*
X303323Y175333D01*
Y163581D01*
G03Y163191I10889J-195D01*
G01Y162548D01*
X303354Y162517D01*
X303372Y162338D01*
Y162337D01*
G03X325102Y163387I10840J1050D01*
G01Y175333D01*
X325253Y175690D01*
X325323Y175760D01*
G03X322999Y200153I-11110J11249D01*
G02X323555Y201984I556J831D01*
G01X372200D01*
G02X372700Y201484I0J-500D01*
G01Y200000D01*
G03X380637Y192063I7937J0D01*
G01X441220D01*
G03X449157Y200000I0J7937D01*
G01Y201484D01*
G02X449657Y201984I500J0D01*
G01X523020D01*
G02X523520Y201484I0J-500D01*
G01Y200000D01*
G03X531457Y192063I7937J0D01*
G01X590512D01*
G03X598449Y200000I0J7937D01*
G01Y201484D01*
G02X598949Y201984I500J0D01*
G01X625418D01*
G02X625907Y201586I0J-500D01*
G01X625945Y201404D01*
X626475Y199134D01*
X627301Y197924D01*
X627473Y197089D01*
X628199Y196610D01*
X628690Y195892D01*
X629527Y195734D01*
X630783Y194906D01*
X633430Y194386D01*
X797954D01*
X798318Y194142D01*
X799562Y194386D01*
X800830D01*
X801140Y194696D01*
X802209Y194906D01*
X803465Y195734D01*
X804302Y195892D01*
X804793Y196610D01*
X805519Y197089D01*
X805691Y197924D01*
X806517Y199134D01*
X807047Y201404D01*
X807085Y201586D01*
G02X807574Y201984I489J-102D01*
G01X816683D01*
G02X817238Y200153I-1J-1000D01*
G03X814913Y175759I8785J-13145D01*
G01X814983Y175689D01*
X815134Y175332D01*
Y163580D01*
G03Y163190I10889J-195D01*
G01Y162547D01*
X815165Y162516D01*
X815183Y162337D01*
Y162336D01*
G03X836913Y163386I10840J1050D01*
G01Y175332D01*
X837064Y175689D01*
X837134Y175759D01*
G03X834809Y200153I-11110J11249D01*
G02X835365Y201984I556J831D01*
G01X1174951D01*
G02X1175506Y200153I-1J-1000D01*
G03X1173181Y175759I8785J-13145D01*
G01X1173251Y175689D01*
X1173402Y175332D01*
Y163580D01*
G03Y163190I10889J-195D01*
G01Y162547D01*
X1173433Y162516D01*
X1173451Y162337D01*
Y162336D01*
G03X1195181Y163386I10840J1050D01*
G01Y175332D01*
X1195332Y175689D01*
X1195402Y175759D01*
G03X1193077Y200153I-11110J11249D01*
G02X1193633Y201984I556J831D01*
G01X1243807D01*
G02X1244307Y201484I0J-500D01*
G01Y200000D01*
G03X1252244Y192063I7937J0D01*
G01X1311299D01*
G03X1319236Y200000I0J7937D01*
G01Y201484D01*
G02X1319736Y201984I500J0D01*
G01X1393098D01*
G02X1393598Y201484I0J-500D01*
G01Y200000D01*
G03X1401535Y192063I7937J0D01*
G01X1460590D01*
G03X1468527Y200000I0J7937D01*
G01Y201484D01*
G02X1469027Y201984I500J0D01*
G01X1495497D01*
G02X1495986Y201586I0J-500D01*
G01X1496024Y201404D01*
X1496554Y199134D01*
X1498769Y195892D01*
X1499606Y195734D01*
X1500862Y194906D01*
X1503509Y194386D01*
X1675630D01*
G02X1679504Y190512I0J-3874D01*
G01Y173678D01*
G03X1679517Y173218I7937J-6D01*
G01X1679518Y173204D01*
Y167935D01*
X1679080Y167497D01*
X1678911D01*
X1678800Y167386D01*
X1671611D01*
X1669268Y165043D01*
Y120016D01*
X1678900D01*
G02X1679400Y119516I0J-500D01*
G01Y40700D01*
X1682700Y37400D01*
X1683728D01*
G02X1684228Y36900I0J-500D01*
G01Y29500D01*
G02X1683728Y29000I-500J0D01*
G01X1683103D01*
X1682905Y29091D01*
X1682834Y29173D01*
G03X1673058Y34602I-12321J-10670D01*
G03X1660604Y5563I-2546J-16098D01*
G01X1660697Y5492D01*
X1660800Y5283D01*
Y4500D01*
G02X1660300Y4000I-500J0D01*
G01X1529075D01*
G02X1528607Y4325I0J500D01*
G03X1528503Y4547I-1408J-524D01*
G01X1528437Y4663D01*
Y4796D01*
G02X1528937Y5296I500J0D01*
G01X1529653D01*
Y16590D01*
X1524553D01*
Y5296D01*
X1525463D01*
G02X1525963Y4796I0J-500D01*
G01Y4663D01*
X1525897Y4547D01*
G03X1525793Y4325I1304J-746D01*
G02X1525325Y4000I-468J175D01*
G01X476246D01*
X475982Y4194D01*
X475933Y4350D01*
G03X473067I-1433J-450D01*
G02X472590Y4000I-477J150D01*
G01X28200D01*
G37*
%LPD*%
G75*
G36*
G01X754466Y123562D02*
X754389Y123624D01*
X754296Y123652D01*
X753860Y124088D01*
Y125372D01*
X754768Y126280D01*
X761052D01*
X761960Y125372D01*
Y124088D01*
X761052Y123180D01*
X754768D01*
X754767Y123181D01*
Y123210D01*
X754654Y123427D01*
X754552Y123497D01*
G02X754466Y123562I862J1230D01*
G37*
G36*
G01X1624544D02*
X1624467Y123624D01*
X1624374Y123652D01*
X1623938Y124088D01*
Y125372D01*
X1624846Y126280D01*
X1631130D01*
X1632038Y125372D01*
Y124088D01*
X1631130Y123180D01*
X1624846D01*
X1624845Y123181D01*
Y123210D01*
X1624732Y123427D01*
X1624630Y123497D01*
G02X1624544Y123562I862J1230D01*
G37*
G36*
G01X430493Y61456D02*
G02X434096Y57853I0J-3603D01*
G01Y55353D01*
G02X427090I-3503J0D01*
G01Y58053D01*
G02X430493Y61456I3403J0D01*
G37*
G36*
G01X579785D02*
G02X583388Y57854I1J-3602D01*
G01Y55354D01*
G02X576382I-3503J0D01*
G01Y58054D01*
G02X579784Y61456I3402J0D01*
G01X579785D01*
G37*
G36*
G01X1300572D02*
G02X1304174Y57854I0J-3602D01*
G01Y55354D01*
G02X1297169I-3503J0D01*
G01X1297170Y58054D01*
G02X1300572Y61456I3402J0D01*
G37*
G36*
G01X1449864Y61455D02*
G02X1453466Y57853I0J-3602D01*
G01Y55353D01*
G02X1446462I-3502J0D01*
G01Y58053D01*
G02X1449864Y61455I3402J0D01*
G37*
G36*
G01X1090725Y18701D02*
Y30449D01*
G03X1090574Y30807I-500J0D01*
G02X1112655I11041J11318D01*
G03X1112504Y30449I349J-358D01*
G01Y18503D01*
G02X1090774Y17454I-10890J0D01*
G01X1090756Y17633D01*
X1090725Y17664D01*
Y18303D01*
G02Y18701I10889J199D01*
G37*
G36*
G01X772772Y18702D02*
Y30450D01*
G03X772621Y30808I-500J0D01*
G02X794702I11041J11318D01*
G03X794551Y30450I349J-358D01*
G01Y18504D01*
G02X772821Y17455I-10890J0D01*
G01X772803Y17634D01*
X772772Y17665D01*
Y18304D01*
G02Y18702I10889J199D01*
G37*
G36*
G01X399703Y23960D02*
X406359D01*
X407531Y22788D01*
Y21132D01*
X406359Y19960D01*
X399703D01*
X398531Y21132D01*
Y22788D01*
X399703Y23960D01*
G37*
G36*
G01X658668Y74450D02*
X664952D01*
X665860Y73542D01*
Y72258D01*
X664952Y71350D01*
X658668D01*
X657760Y72258D01*
Y73542D01*
X658668Y74450D01*
G37*
G36*
G01X756287D02*
X762571D01*
X763479Y73542D01*
Y72258D01*
X762571Y71350D01*
X756287D01*
X755379Y72258D01*
Y73542D01*
X756287Y74450D01*
G37*
G36*
G01X1528746D02*
X1535030D01*
X1535938Y73542D01*
Y72258D01*
X1535030Y71350D01*
X1528746D01*
X1527838Y72258D01*
Y73542D01*
X1528746Y74450D01*
G37*
G36*
G01X1626365D02*
X1632649D01*
X1633557Y73542D01*
Y72258D01*
X1632649Y71350D01*
X1626365D01*
X1625457Y72258D01*
Y73542D01*
X1626365Y74450D01*
G37*
G36*
G01X653758Y98650D02*
X655042D01*
X655950Y97742D01*
Y91458D01*
X655042Y90550D01*
X653758D01*
X652850Y91458D01*
Y97742D01*
X653758Y98650D01*
G37*
G36*
G01X701028D02*
X702312D01*
X703220Y97742D01*
Y91458D01*
X702312Y90550D01*
X701028D01*
X700120Y91458D01*
Y97742D01*
X701028Y98650D01*
G37*
G36*
G01X1523836D02*
X1525120D01*
X1526028Y97742D01*
Y91458D01*
X1525120Y90550D01*
X1523836D01*
X1522928Y91458D01*
Y97742D01*
X1523836Y98650D01*
G37*
G36*
G01X1571106D02*
X1572390D01*
X1573298Y97742D01*
Y91458D01*
X1572390Y90550D01*
X1571106D01*
X1570198Y91458D01*
Y97742D01*
X1571106Y98650D01*
G37*
G36*
G01X777558Y98680D02*
X778842D01*
X779750Y97772D01*
Y91488D01*
X778842Y90580D01*
X777558D01*
X776650Y91488D01*
Y97772D01*
X777558Y98680D01*
G37*
G36*
G01X1647636D02*
X1648920D01*
X1649828Y97772D01*
Y91488D01*
X1648920Y90580D01*
X1647636D01*
X1646728Y91488D01*
Y97772D01*
X1647636Y98680D01*
G37*
G36*
G01X746838Y94380D02*
X753122D01*
X754030Y93472D01*
Y92188D01*
X753122Y91280D01*
X746838D01*
X745930Y92188D01*
Y93472D01*
X746838Y94380D01*
G37*
G36*
G01X1616916D02*
X1623200D01*
X1624108Y93472D01*
Y92188D01*
X1623200Y91280D01*
X1616916D01*
X1616008Y92188D01*
Y93472D01*
X1616916Y94380D01*
G37*
G36*
G01X671996Y94840D02*
X678280D01*
X679188Y93932D01*
Y92648D01*
X678280Y91740D01*
X671996D01*
X671088Y92648D01*
Y93932D01*
X671996Y94840D01*
G37*
G36*
G01X1542074D02*
X1548358D01*
X1549266Y93932D01*
Y92648D01*
X1548358Y91740D01*
X1542074D01*
X1541166Y92648D01*
Y93932D01*
X1542074Y94840D01*
G37*
G36*
G01X723758Y107150D02*
X730042D01*
X730950Y106242D01*
Y104958D01*
X730042Y104050D01*
X723758D01*
X722850Y104958D01*
Y106242D01*
X723758Y107150D01*
G37*
G36*
G01X1593836D02*
X1600120D01*
X1601028Y106242D01*
Y104958D01*
X1600120Y104050D01*
X1593836D01*
X1592928Y104958D01*
Y106242D01*
X1593836Y107150D01*
G37*
G36*
G01X724668Y116940D02*
X730952D01*
X731860Y116032D01*
Y114748D01*
X730952Y113840D01*
X724668D01*
X723760Y114748D01*
Y116032D01*
X724668Y116940D01*
G37*
G36*
G01X1594746D02*
X1601030D01*
X1601938Y116032D01*
Y114748D01*
X1601030Y113840D01*
X1594746D01*
X1593838Y114748D01*
Y116032D01*
X1594746Y116940D01*
G37*
G36*
G01X1634239Y121880D02*
X1640523D01*
X1641431Y120972D01*
Y119688D01*
X1640523Y118780D01*
X1634239D01*
X1633331Y119688D01*
Y120972D01*
X1634239Y121880D01*
G37*
G36*
G01X745263Y122002D02*
X751547D01*
X752455Y121094D01*
Y119810D01*
X751547Y118902D01*
X745263D01*
X744355Y119810D01*
Y121094D01*
X745263Y122002D01*
G37*
G36*
G01X1615341D02*
X1621625D01*
X1622533Y121094D01*
Y119810D01*
X1621625Y118902D01*
X1615341D01*
X1614433Y119810D01*
Y121094D01*
X1615341Y122002D01*
G37*
G36*
G01X660972Y122550D02*
X667256D01*
X668164Y121642D01*
Y120358D01*
X667256Y119450D01*
X660972D01*
X660064Y120358D01*
Y121642D01*
X660972Y122550D01*
G37*
G36*
G01X1531050D02*
X1537334D01*
X1538242Y121642D01*
Y120358D01*
X1537334Y119450D01*
X1531050D01*
X1530142Y120358D01*
Y121642D01*
X1531050Y122550D01*
G37*
G36*
G01X689319Y123580D02*
X695603D01*
X696511Y122672D01*
Y121388D01*
X695603Y120480D01*
X689319D01*
X688411Y121388D01*
Y122672D01*
X689319Y123580D01*
G37*
G36*
G01X1559397D02*
X1565681D01*
X1566589Y122672D01*
Y121388D01*
X1565681Y120480D01*
X1559397D01*
X1558489Y121388D01*
Y122672D01*
X1559397Y123580D01*
G37*
G36*
G01X670421Y127480D02*
X676705D01*
X677613Y126572D01*
Y125288D01*
X676705Y124380D01*
X670421D01*
X669513Y125288D01*
Y126572D01*
X670421Y127480D01*
G37*
G36*
G01X1540499D02*
X1546783D01*
X1547691Y126572D01*
Y125288D01*
X1546783Y124380D01*
X1540499D01*
X1539591Y125288D01*
Y126572D01*
X1540499Y127480D01*
G37*
G36*
G01X679970Y131150D02*
X686254D01*
X687162Y130242D01*
Y128958D01*
X686254Y128050D01*
X679970D01*
X679062Y128958D01*
Y130242D01*
X679970Y131150D01*
G37*
G36*
G01X1550048D02*
X1556332D01*
X1557240Y130242D01*
Y128958D01*
X1556332Y128050D01*
X1550048D01*
X1549140Y128958D01*
Y130242D01*
X1550048Y131150D01*
G37*
G36*
G01X764161Y121880D02*
X770445D01*
X771353Y120972D01*
Y119653D01*
X770480Y118780D01*
X764161D01*
X763253Y119688D01*
Y120972D01*
X764161Y121880D01*
G37*
G36*
G01X521300Y14800D02*
Y21400D01*
X522500Y22600D01*
X524100D01*
X525300Y21400D01*
Y14700D01*
X524100Y13500D01*
X522600D01*
X521300Y14800D01*
G37*
G36*
G01X566700Y21700D02*
Y23300D01*
X567900Y24500D01*
X574600D01*
X575700Y23400D01*
Y21600D01*
X574500Y20400D01*
X568000D01*
X566700Y21700D01*
G37*
G36*
G01X445900Y35300D02*
Y37000D01*
X447100Y38200D01*
X454400D01*
X455500Y37100D01*
Y35400D01*
X454200Y34100D01*
X447100D01*
X445900Y35300D01*
G37*
G36*
G01X1315900Y35400D02*
Y37000D01*
X1317100Y38200D01*
X1324400D01*
X1325600Y37000D01*
Y35400D01*
X1324400Y34200D01*
X1317100D01*
X1315900Y35400D01*
G37*
G36*
G01X1268600Y21200D02*
Y22800D01*
X1269800Y24000D01*
X1276400D01*
X1277600Y22800D01*
Y21000D01*
X1276500Y19900D01*
X1269900D01*
X1268600Y21200D01*
G37*
G36*
G01X1436800Y21700D02*
Y23300D01*
X1438000Y24500D01*
X1444700D01*
X1445800Y23400D01*
Y21700D01*
X1444500Y20400D01*
X1438100D01*
X1436800Y21700D01*
G37*
G36*
G01X1391400Y14800D02*
Y21500D01*
X1392500Y22600D01*
X1394200D01*
X1395400Y21400D01*
Y14700D01*
X1394200Y13500D01*
X1392700D01*
X1391400Y14800D01*
G37*
G36*
G01X83188Y71770D02*
X82328D01*
G02X82327Y73896I3538J1065D01*
G01X83185D01*
G03X83617Y74144I0J500D01*
G02X84604Y75110I2248J-1310D01*
G03X84862Y75548I-242J438D01*
G01Y76390D01*
G02X86870I1004J-3555D01*
G01Y75548D01*
G03X87128Y75110I500J0D01*
G02X88119Y74136I-1262J-2275D01*
G03X88552Y73886I433J250D01*
G01X89408D01*
G02X89560Y72835I-3542J-1049D01*
G02X89404Y71770I-3694J-3D01*
G01X88544D01*
G03X88112Y71522I0J-500D01*
G02X87126Y70559I-2246J1313D01*
G03X86868Y70121I242J-438D01*
G01Y69279D01*
G02X84864I-1002J3556D01*
G01Y70121D01*
G03X84606Y70559I-500J0D01*
G02X83620Y71522I1260J2276D01*
G03X83188Y71770I-432J-252D01*
G37*
G36*
G01Y103266D02*
X82328D01*
G02X82327Y105392I3538J1065D01*
G01X83185D01*
G03X83617Y105640I0J500D01*
G02X84604Y106606I2248J-1310D01*
G03X84862Y107044I-242J438D01*
G01Y107886D01*
G02X86870I1004J-3555D01*
G01Y107044D01*
G03X87128Y106606I500J0D01*
G02X88119Y105632I-1262J-2275D01*
G03X88552Y105382I433J250D01*
G01X89408D01*
G02X89560Y104331I-3542J-1049D01*
G02X89404Y103266I-3694J-3D01*
G01X88544D01*
G03X88112Y103018I0J-500D01*
G02X87126Y102055I-2246J1313D01*
G03X86868Y101617I242J-438D01*
G01Y100775D01*
G02X84864I-1002J3556D01*
G01Y101617D01*
G03X84606Y102055I-500J0D01*
G02X83620Y103018I1260J2276D01*
G03X83188Y103266I-432J-252D01*
G37*
G54D39*
X1336729Y49150D03*
X466650D03*
X1376099Y44032D03*
X506020D03*
X1336729Y32615D03*
X466650D03*
X1376099Y27497D03*
X506020D03*
G54D38*
X1550725Y49150D03*
X1534977D03*
X1519229D03*
X680646D03*
X664898D03*
X649150D03*
X1550725Y32614D03*
X1534977D03*
X1519229D03*
X680646D03*
X664898D03*
X649150D03*
X1550725Y16078D03*
X1519229D03*
X680646D03*
X649150D03*
G54D40*
X1558599Y44015D03*
X1542851D03*
X1527103D03*
X688520D03*
X672772D03*
X657024D03*
X1558599Y27479D03*
X1542851D03*
X1527103D03*
X688520D03*
X672772D03*
X657024D03*
X1558599Y10943D03*
X688520D03*
X657024D03*
G54D42*
X1647618Y132244D03*
X1572775D03*
X777539D03*
X702697D03*
G54D48*
X40827Y147638D03*
Y29528D03*
G54D43*
X1600374Y132244D03*
X1525531D03*
X1412164Y56653D03*
X1262872Y56654D03*
X730295Y132244D03*
X655453D03*
X542085Y56654D03*
X392793Y56653D03*
G54D44*
X1378938Y176650D03*
X508859D03*
G54D45*
X1333938D03*
X463859D03*
G54D46*
X1221732Y37400D03*
G54D41*
X1291985Y40500D03*
X1273087D03*
X571198D03*
X552300D03*
X1441277Y40499D03*
X1422379D03*
X421906D03*
X403008D03*
G54D47*
X351654Y37401D03*
G54D21*
X99100Y127470D03*
X120500Y59400D03*
X114400Y59700D03*
X107500Y59500D03*
X102400Y59600D03*
X111958Y73600D03*
X121958Y70900D03*
X116958Y68600D03*
X106958Y68500D03*
X102590Y115680D03*
X115400Y120270D03*
X107390Y125110D03*
X119800Y124390D03*
X108900Y137300D03*
X114300Y134900D03*
X119700Y132400D03*
X111500Y129900D03*
X128600Y114510D03*
X132500Y110100D03*
X125000Y126400D03*
X141400Y164800D03*
X129000D03*
X169200Y165200D03*
X155500Y164800D03*
X183300Y164700D03*
X346800Y113500D03*
X345400Y107600D03*
X346200Y102500D03*
X350700Y121642D03*
X345900Y125100D03*
X347350Y143750D03*
X346906Y137693D03*
X362500Y97100D03*
X357600Y97000D03*
X357800Y114657D03*
X357600Y108561D03*
X356861Y102961D03*
X367200Y124000D03*
X397800Y23600D03*
Y19500D03*
X398307Y35000D03*
Y46100D03*
X396732Y78932D03*
X417900Y6700D03*
X414900Y6500D03*
X410200Y6700D03*
X404400Y6800D03*
X408200Y23500D03*
Y19900D03*
X405531Y21960D03*
X400531D03*
X400100Y13900D03*
X412800Y16200D03*
X417205Y35000D03*
X407600D03*
X407756Y46100D03*
X417205D03*
X410906D03*
X414055Y46200D03*
X412480Y80900D03*
X403032Y89532D03*
X415630Y80700D03*
X412300Y85600D03*
X421929Y78400D03*
X409331Y88600D03*
X406181Y82300D03*
X399882Y79318D03*
X426500Y35000D03*
X426654Y46100D03*
X426200Y78100D03*
X446000Y38400D03*
Y33900D03*
X455400Y34000D03*
Y38600D03*
X447880Y36200D03*
X453480D03*
X465600Y55900D03*
X463435Y79865D03*
X453900Y92300D03*
X466200Y87558D03*
X453300Y86800D03*
X451100Y81400D03*
X452100Y97000D03*
X466100Y83258D03*
X452000Y102200D03*
X466300Y100900D03*
X474500Y3900D03*
X490200Y4000D03*
X488800Y73700D03*
X488000Y89800D03*
X477630Y88900D03*
X488800Y93800D03*
X507200Y4200D03*
X505700Y90200D03*
X511600Y108000D03*
X520900Y22500D03*
X525600Y22600D03*
Y13900D03*
X520800Y13800D03*
X523300Y15580D03*
Y20580D03*
X525700Y99300D03*
X519400Y96400D03*
X520439Y91000D03*
X516500Y87442D03*
X559425Y13575D03*
X560198Y46100D03*
X556900Y35000D03*
X547599D03*
X557048Y46100D03*
X547599D03*
X558623Y79200D03*
X552324Y78500D03*
X546024Y79200D03*
X549174Y89400D03*
X575600Y7600D03*
X571500Y7500D03*
X567500Y7300D03*
X563100Y7200D03*
X582416Y16466D03*
X567100Y20500D03*
X575900Y20800D03*
X575800Y24300D03*
X567000Y24400D03*
X573721Y22500D03*
X568721D03*
X563347Y46100D03*
X575946D03*
X566497D03*
X575800Y35000D03*
X566497D03*
X571221Y79700D03*
X568072Y81500D03*
X564922Y81900D03*
X561772Y80800D03*
X574371Y78400D03*
X563800Y87700D03*
X604400Y96000D03*
X604200Y107400D03*
X614900Y90157D03*
X615600Y95139D03*
X626100Y99900D03*
X625600Y95400D03*
X625700Y90100D03*
X615500Y100157D03*
X622658Y112158D03*
X622200Y120258D03*
X626600Y106100D03*
X615500Y105157D03*
X626173Y148400D03*
X617949Y147000D03*
X648300Y55600D03*
X651500Y94700D03*
X651100Y91100D03*
X655200Y4100D03*
X661600Y75900D03*
X667200Y75700D03*
X665100Y55900D03*
X659310Y72900D03*
X664310D03*
X654400Y92100D03*
Y97100D03*
X670414Y96486D03*
X672638Y93290D03*
X666614Y121000D03*
X661614D03*
X658400Y102500D03*
X659390Y117490D03*
X668839Y117661D03*
X671063Y125930D03*
X676063D03*
X667500Y126200D03*
X688800Y4100D03*
X680300Y75600D03*
X681600Y55500D03*
X698400Y90300D03*
X689723Y89400D03*
X689311Y96311D03*
X679862Y96538D03*
X677638Y93290D03*
X678288Y122700D03*
X697185Y117385D03*
X687736Y118700D03*
X689961Y122030D03*
X694961D03*
X685600Y133200D03*
X680900D03*
X680612Y129600D03*
X685612D03*
X701100Y16900D03*
X701670Y97100D03*
Y92100D03*
X701732Y101968D03*
X740300Y87300D03*
X735807Y96593D03*
X745256Y96044D03*
X724400Y105600D03*
X729400D03*
X730310Y115390D03*
X725310D03*
X743681Y117400D03*
X731950Y111850D03*
X723500Y118900D03*
X722400Y102300D03*
X730900Y108900D03*
X753100Y75100D03*
X765600Y74800D03*
X761929Y72900D03*
X756929D03*
X752480Y92830D03*
X747480D03*
X764153Y96153D03*
X754704Y96196D03*
X745905Y120452D03*
X750905D03*
X762578Y117300D03*
X753130D03*
X754300Y121400D03*
X764803Y120330D03*
X764000Y124700D03*
X760410Y124730D03*
X755410D03*
X774600Y90300D03*
X778200Y92130D03*
Y97130D03*
X776032Y101968D03*
X772027Y117300D03*
X769803Y120330D03*
X1223200Y99000D03*
X1218000Y99100D03*
X1216500Y119500D03*
X1216700Y114400D03*
X1216500Y108300D03*
X1216400Y102600D03*
X1226900Y119561D03*
Y114043D03*
X1227000Y108361D03*
X1227100Y102861D03*
X1219600Y129400D03*
X1219400Y123900D03*
X1211200Y144900D03*
X1217405Y143895D03*
X1229800Y96400D03*
X1238900Y123300D03*
X1238100Y127900D03*
X1273000Y6100D03*
X1270610Y21960D03*
X1267700Y22900D03*
Y19700D03*
X1268700Y14000D03*
X1268386Y35000D03*
Y46100D03*
X1266811Y78300D03*
X1273111Y89100D03*
X1269961Y78400D03*
X1276700Y5900D03*
X1280900D03*
X1285800D03*
X1278700Y19800D03*
Y23000D03*
X1275610Y21960D03*
X1289775Y11975D03*
X1296600Y35000D03*
X1277700D03*
X1287284D03*
X1296733Y46100D03*
X1287284D03*
X1277835D03*
X1284134D03*
X1280985Y46200D03*
X1295158Y79158D03*
X1292008Y80192D03*
X1288859Y78400D03*
X1279410Y87200D03*
X1285709Y84300D03*
X1276260Y79000D03*
X1282559Y85700D03*
X1315879Y38200D03*
X1315979Y33900D03*
X1317959Y36200D03*
X1323559D03*
X1325279Y38600D03*
Y33800D03*
X1335300Y55600D03*
X1340400Y90800D03*
X1333400Y82900D03*
X1323000Y99239D03*
X1321400Y92800D03*
X1329500Y81400D03*
X1321500Y82600D03*
X1322500Y87800D03*
X1335600Y96500D03*
X1360600Y4000D03*
X1344700Y4100D03*
X1358200Y69000D03*
X1358600Y73700D03*
X1359000Y91000D03*
X1345100Y105500D03*
X1376300Y4000D03*
X1371600Y86463D03*
X1387400Y87242D03*
X1389900Y97600D03*
X1371600Y96000D03*
X1395679Y22600D03*
X1390979Y22500D03*
X1390879Y13800D03*
X1395679Y13900D03*
X1393379Y20580D03*
Y15580D03*
X1395200Y99500D03*
X1391000Y92400D03*
X1433700Y8000D03*
X1429525Y13775D03*
X1417678Y46100D03*
X1427127D03*
X1417678Y35000D03*
X1427000D03*
X1433426Y46100D03*
X1430277D03*
X1416103Y78400D03*
X1422403D03*
X1434200Y88100D03*
X1435001Y81700D03*
X1431851Y80200D03*
X1428702Y79002D03*
X1429400Y88500D03*
X1442400Y8200D03*
X1438000Y8100D03*
X1446300Y8300D03*
X1436500Y23900D03*
Y20700D03*
X1445900Y20800D03*
X1445700Y24400D03*
X1443800Y22500D03*
X1438800D03*
X1454600Y17600D03*
X1446025Y46100D03*
X1436576D03*
X1445900Y35000D03*
X1436576D03*
X1444450Y78300D03*
X1441300Y79100D03*
X1438151Y81100D03*
X1472400Y102700D03*
X1474200Y106600D03*
X1494200Y97800D03*
X1495000Y92800D03*
X1484700Y93057D03*
X1485000Y98057D03*
X1494700Y111200D03*
X1494500Y102700D03*
X1484900Y103257D03*
X1492300Y117558D03*
X1484800Y109357D03*
X1492042Y126358D03*
X1495800Y147800D03*
X1487600Y147000D03*
X1527200Y3800D03*
X1518200Y55600D03*
X1524478Y97100D03*
Y92100D03*
X1521579Y94700D03*
X1521179Y91100D03*
X1534388Y72900D03*
X1529388D03*
X1550500Y75500D03*
X1537279Y75700D03*
X1531679Y75900D03*
X1535300Y55800D03*
X1542716Y93290D03*
X1547716D03*
X1549940Y96538D03*
X1540492Y96486D03*
X1531692Y121000D03*
X1528478Y102500D03*
X1548366Y122700D03*
X1538917Y117661D03*
X1529468Y117490D03*
X1536692Y121000D03*
X1546141Y125930D03*
X1550690Y129600D03*
X1550979Y133200D03*
X1537579Y126200D03*
X1541141Y125930D03*
X1559000Y4200D03*
X1570800Y18900D03*
X1551800Y55700D03*
X1571748Y92100D03*
Y97100D03*
X1559802Y89400D03*
X1559389Y96311D03*
X1568479Y90300D03*
X1571810Y101968D03*
X1557814Y118700D03*
X1567263Y117385D03*
X1565039Y122030D03*
X1560039D03*
X1555690Y129600D03*
X1555679Y133200D03*
X1594478Y105600D03*
X1592900Y101700D03*
X1593300Y119000D03*
X1595388Y115390D03*
X1617558Y92830D03*
X1610379Y87300D03*
X1605885Y96593D03*
X1615334Y96044D03*
X1599478Y105600D03*
X1600388Y115390D03*
X1613759Y117400D03*
X1602028Y111850D03*
X1600900Y108700D03*
X1615983Y120452D03*
X1635679Y74800D03*
X1623179Y75100D03*
X1627007Y72900D03*
X1632007D03*
X1622558Y92830D03*
X1624782Y96196D03*
X1634231Y96153D03*
X1620983Y120452D03*
X1639881Y120330D03*
X1623208Y117300D03*
X1642105D03*
X1632656D03*
X1624300Y121500D03*
X1634881Y120330D03*
X1625488Y124730D03*
X1630488D03*
X1634179Y124300D03*
X1648278Y97130D03*
X1644679Y90300D03*
X1648278Y92130D03*
X1646110Y101968D03*
X1676100Y78900D03*
G54D22*
X123100Y49600D03*
X143300Y27300D03*
X143800Y53600D03*
X144500Y40000D03*
X133100Y71300D03*
X144200Y96300D03*
X143000Y105700D03*
X141900Y154700D03*
X134800Y164000D03*
X144700Y149200D03*
X137100Y158600D03*
X137000Y170400D03*
X127400D03*
X150300Y20200D03*
X166500Y34700D03*
X153100Y49600D03*
X148800Y85000D03*
X163500Y144900D03*
X150300Y144600D03*
X156000Y138200D03*
X156500Y144800D03*
X169900Y146800D03*
X164400Y138200D03*
X169400Y153600D03*
X155600Y157900D03*
X162100Y164300D03*
X168000Y161200D03*
X149300Y164100D03*
X163200Y151600D03*
X162000Y159400D03*
X148000Y158800D03*
X152600Y152000D03*
X155900Y170000D03*
X163800Y170100D03*
X148600D03*
X180300Y20200D03*
X183100Y49600D03*
X191700Y75400D03*
X175000Y62300D03*
X174200Y96300D03*
X190400Y136600D03*
X191200Y142400D03*
X178100Y144600D03*
X184000Y138800D03*
X173600Y138700D03*
X185800Y145400D03*
X190000Y149800D03*
X179300Y156400D03*
X187100Y155800D03*
X192100Y163500D03*
X176300Y164400D03*
X175500Y151300D03*
X173700Y158700D03*
X190400Y169800D03*
X182600Y152000D03*
X171300Y170000D03*
X177800Y170400D03*
X210300Y20200D03*
X213100Y49600D03*
X209400Y60900D03*
X204200Y96300D03*
X196200Y102300D03*
X211300Y138600D03*
X204200Y139200D03*
X195900Y146300D03*
X213300Y146800D03*
X197300Y139100D03*
X205100Y147700D03*
X201500Y154400D03*
X213500Y155400D03*
X197100Y160800D03*
X194600Y154800D03*
X227100Y43000D03*
X234200Y96300D03*
X225600Y104500D03*
X234500Y138700D03*
X230600Y146400D03*
X218100Y140500D03*
X224400Y138200D03*
X236800Y165000D03*
X238800Y157500D03*
X231600Y155100D03*
X221800Y149400D03*
X236500Y185900D03*
X235400Y172900D03*
X240300Y20200D03*
X243100Y49600D03*
X248600Y142900D03*
X242600Y140100D03*
X254400Y138200D03*
X239600Y148700D03*
X245100Y165200D03*
X255400Y148400D03*
X245600Y157000D03*
X248400Y149800D03*
X239800Y178700D03*
X243300Y185600D03*
X242300Y171800D03*
X252600Y192000D03*
X242400Y193300D03*
X270300Y20200D03*
X273100Y49600D03*
X264200Y96300D03*
X262900Y104900D03*
X284400Y138200D03*
X265300Y170000D03*
X282600Y192000D03*
X294200Y96300D03*
X287600Y150000D03*
X292800Y169800D03*
X324200Y96300D03*
X314600Y104100D03*
X310200Y135900D03*
X338300Y162900D03*
Y183800D03*
X359200Y164900D03*
X359100Y184400D03*
X466654Y7874D03*
Y29922D03*
Y24410D03*
Y18898D03*
Y13386D03*
Y51969D03*
Y46457D03*
Y40945D03*
Y35433D03*
X474528Y8268D03*
X482402Y7874D03*
X490276Y8268D03*
X474528Y30315D03*
X482402Y29922D03*
X490276Y30315D03*
X474528Y24803D03*
X482402Y24410D03*
X490276Y24803D03*
X474528Y19292D03*
X482402Y18898D03*
X490276Y19292D03*
X474528Y13780D03*
X482402Y13386D03*
X490276Y13780D03*
X474528Y52362D03*
X482402Y51969D03*
X490276Y52362D03*
X474528Y46851D03*
X482402Y46457D03*
X490276Y46851D03*
X474528Y41339D03*
X482402Y40945D03*
X490276Y41339D03*
X474528Y35827D03*
X482402Y35433D03*
X490276Y35827D03*
X498150Y7874D03*
X506024Y8268D03*
X498150Y29922D03*
X506024Y30315D03*
X498150Y24410D03*
X506024Y24803D03*
X498150Y18898D03*
X506024Y19292D03*
X498150Y13386D03*
X506024Y13780D03*
X498150Y51969D03*
X506024Y52362D03*
X498150Y46457D03*
X506024Y46851D03*
X498150Y40945D03*
X506024Y41339D03*
X498150Y35433D03*
X506024Y35827D03*
X649173Y7874D03*
Y29922D03*
Y24410D03*
Y18898D03*
Y13386D03*
Y51969D03*
Y46457D03*
Y40945D03*
Y35433D03*
X657047Y8268D03*
X664921Y7874D03*
X672795Y8268D03*
X657047Y30315D03*
X664921Y29922D03*
X672795Y30315D03*
X657047Y24803D03*
X664921Y24410D03*
X672795Y24803D03*
X657047Y19292D03*
X664921Y18898D03*
X672795Y19292D03*
X657047Y13780D03*
X664921Y13386D03*
X672795Y13780D03*
X657047Y52362D03*
X664921Y51969D03*
X672795Y52362D03*
X657047Y46851D03*
X664921Y46457D03*
X672795Y46851D03*
X657047Y41339D03*
X664921Y40945D03*
X672795Y41339D03*
X657047Y35827D03*
X664921Y35433D03*
X672795Y35827D03*
X680669Y7874D03*
X688543Y8268D03*
X680669Y29922D03*
X688543Y30315D03*
X680669Y24410D03*
X688543Y24803D03*
X680669Y18898D03*
X688543Y19292D03*
X680669Y13386D03*
X688543Y13780D03*
X680669Y51969D03*
X688543Y52362D03*
X680669Y46457D03*
X688543Y46851D03*
X680669Y40945D03*
X688543Y41339D03*
X680669Y35433D03*
X688543Y35827D03*
X806800Y26700D03*
X810700Y65200D03*
X836800Y26700D03*
X825200Y111700D03*
X840700Y65200D03*
X855200Y111700D03*
X855400Y173000D03*
X866800Y26700D03*
X870700Y65200D03*
X896800Y26700D03*
X900700Y65200D03*
X885200Y111700D03*
X885400Y173000D03*
X926800Y26700D03*
X915200Y111700D03*
X915400Y173000D03*
X930700Y65200D03*
X945200Y111700D03*
X945400Y173000D03*
X956800Y26700D03*
X960700Y65200D03*
X975200Y111700D03*
X975400Y173000D03*
X986800Y26700D03*
X990700Y65200D03*
X1018800Y26300D03*
X1005200Y111700D03*
X1005400Y173000D03*
X1022700Y64800D03*
X1037200Y111300D03*
X1035400Y173000D03*
X1048800Y26300D03*
X1052700Y64800D03*
X1067200Y111300D03*
X1067400Y172600D03*
X1078800Y26300D03*
X1082700Y64800D03*
X1097200Y111300D03*
X1097400Y172600D03*
X1136600Y19700D03*
X1135400Y41000D03*
X1127200Y111300D03*
X1127400Y172600D03*
X1157400D03*
X1336733Y7874D03*
X1344607Y8268D03*
X1336733Y29922D03*
X1344607Y30315D03*
X1336733Y24410D03*
X1344607Y24803D03*
X1336733Y18898D03*
X1344607Y19292D03*
X1336733Y13386D03*
X1344607Y13780D03*
X1336733Y51969D03*
X1344607Y52362D03*
X1336733Y46457D03*
X1344607Y46851D03*
X1336733Y40945D03*
X1344607Y41339D03*
X1336733Y35433D03*
X1344607Y35827D03*
X1352481Y7874D03*
X1360355Y8268D03*
X1352481Y29922D03*
X1360355Y30315D03*
X1352481Y24410D03*
X1360355Y24803D03*
X1352481Y18898D03*
X1360355Y19292D03*
X1352481Y13386D03*
X1360355Y13780D03*
X1352481Y51969D03*
X1360355Y52362D03*
X1352481Y46457D03*
X1360355Y46851D03*
X1352481Y40945D03*
X1360355Y41339D03*
X1352481Y35433D03*
X1360355Y35827D03*
X1368229Y7874D03*
X1376103Y8268D03*
X1368229Y29922D03*
X1376103Y30315D03*
X1368229Y24410D03*
X1376103Y24803D03*
X1368229Y18898D03*
X1376103Y19292D03*
X1368229Y13386D03*
X1376103Y13780D03*
X1368229Y51969D03*
X1376103Y52362D03*
X1368229Y46457D03*
X1376103Y46851D03*
X1368229Y40945D03*
X1376103Y41339D03*
X1368229Y35433D03*
X1376103Y35827D03*
X1519252Y7874D03*
X1527126Y8268D03*
X1519252Y29922D03*
X1527126Y30315D03*
X1519252Y24410D03*
X1527126Y24803D03*
X1519252Y18898D03*
X1527126Y19292D03*
X1519252Y13386D03*
X1527126Y13780D03*
X1519252Y51969D03*
X1527126Y52362D03*
X1519252Y46457D03*
X1527126Y46851D03*
X1519252Y40945D03*
X1527126Y41339D03*
X1519252Y35433D03*
X1527126Y35827D03*
X1535000Y7874D03*
X1542874Y8268D03*
X1550748Y7874D03*
X1535000Y29922D03*
X1542874Y30315D03*
X1550748Y29922D03*
X1535000Y24410D03*
X1542874Y24803D03*
X1550748Y24410D03*
X1535000Y18898D03*
X1542874Y19292D03*
X1550748Y18898D03*
X1535000Y13386D03*
X1542874Y13780D03*
X1550748Y13386D03*
X1535000Y51969D03*
X1542874Y52362D03*
X1550748Y51969D03*
X1535000Y46457D03*
X1542874Y46851D03*
X1550748Y46457D03*
X1535000Y40945D03*
X1542874Y41339D03*
X1550748Y40945D03*
X1535000Y35433D03*
X1542874Y35827D03*
X1550748Y35433D03*
X1558622Y8268D03*
Y30315D03*
Y24803D03*
Y19292D03*
Y13780D03*
Y52362D03*
Y46851D03*
Y41339D03*
Y35827D03*
G54D24*
X343780Y11810D03*
Y19684D03*
Y27558D03*
X335906Y11810D03*
Y19684D03*
Y27558D03*
X343780Y43306D03*
Y51180D03*
X335906Y43306D03*
Y51180D03*
X343780Y59054D03*
X335906D03*
X1205984Y11810D03*
Y19684D03*
Y27558D03*
Y43306D03*
Y51180D03*
Y59054D03*
X1213858Y11810D03*
Y19684D03*
Y27558D03*
Y43306D03*
Y51180D03*
Y59054D03*
G54D10*
X8221Y28000D03*
Y9008D03*
X4287Y18504D03*
X17717Y5074D03*
X27213Y28000D03*
X31147Y18504D03*
X27213Y9008D03*
X17717Y31934D03*
X1661016Y28000D03*
Y9008D03*
X1657082Y18504D03*
X1670512Y5074D03*
X1680008Y28000D03*
X1683942Y18504D03*
X1680008Y9008D03*
X1670512Y31934D03*
G54D29*
X383642Y40532D03*
Y79902D03*
X396122Y99587D03*
X383642Y119272D03*
Y158642D03*
X417382Y99587D03*
X405964Y178327D03*
X439744Y99587D03*
Y138957D03*
Y178327D03*
X532934Y40532D03*
Y79902D03*
Y119272D03*
Y158642D03*
X545414Y99587D03*
X555256Y178327D03*
X566674Y99587D03*
X589036D03*
Y138957D03*
Y178327D03*
X1253721Y40532D03*
Y79902D03*
Y119272D03*
Y158642D03*
X1266201Y99587D03*
X1276043Y178327D03*
X1287461Y99587D03*
X1309823D03*
Y138957D03*
Y178327D03*
X1403012Y40532D03*
Y79902D03*
Y119272D03*
Y158642D03*
X1415492Y99587D03*
X1436752D03*
X1425334Y178327D03*
X1459114Y99587D03*
Y138957D03*
Y178327D03*
G54D31*
X439744Y60217D03*
X589036D03*
X1309823D03*
X1459114D03*
G54D16*
X56339Y41339D03*
Y53150D03*
Y64961D03*
Y76772D03*
Y88583D03*
Y100394D03*
Y112205D03*
Y124016D03*
X44528Y135827D03*
X56339D03*
G54D19*
X85866Y72835D03*
Y104331D03*
G54D14*
X40827Y29528D03*
Y147638D03*
G54D32*
X468859Y115666D03*
Y141650D03*
X488859Y115666D03*
X478859D03*
X483859Y125666D03*
X473859D03*
X478859Y141650D03*
X488859D03*
X473859Y151650D03*
X483859D03*
X498859Y115666D03*
X503859Y125666D03*
X493859D03*
X498859Y141650D03*
X493859Y151650D03*
X503859D03*
X1338938Y115666D03*
X1343938Y125666D03*
X1338938Y141650D03*
X1343938Y151650D03*
X1358938Y115666D03*
X1348938D03*
X1363938Y125666D03*
X1353938D03*
X1348938Y141650D03*
X1358938D03*
X1353938Y151650D03*
X1363938D03*
X1368938Y115666D03*
X1373938Y125666D03*
X1368938Y141650D03*
X1373938Y151650D03*
G54D36*
X641212Y132244D03*
X791764D03*
X1511291D03*
X1661843D03*
G54D11*
X9088Y80158D03*
Y91958D03*
X19088Y80158D03*
Y91958D03*
X109288Y92458D03*
X119288D03*
X109288Y103958D03*
X119288D03*
G54D27*
X392776Y32264D03*
X383642Y50375D03*
Y70060D03*
Y88564D03*
X411673Y32264D03*
X430571D03*
X439744Y50375D03*
Y70060D03*
Y88564D03*
X532934Y50375D03*
Y70060D03*
Y88564D03*
X542068Y32264D03*
X560965D03*
X579863D03*
X589036Y50375D03*
Y70060D03*
Y88564D03*
X1262855Y32264D03*
X1253721Y50375D03*
Y70060D03*
Y88564D03*
X1281752Y32264D03*
X1300650D03*
X1309823Y50375D03*
Y70060D03*
Y88564D03*
X1412146Y32264D03*
X1403012Y50375D03*
Y70060D03*
Y88564D03*
X1431043Y32264D03*
X1449941D03*
X1459114Y50375D03*
Y70060D03*
Y88564D03*
G54D28*
X392795Y56653D03*
X542087Y56654D03*
X655453Y132244D03*
X702697D03*
X730295D03*
X777539D03*
X1262874Y56654D03*
X1412166Y56653D03*
X1525531Y132244D03*
X1572775D03*
X1600374D03*
X1647618D03*
G54D20*
X81929Y76772D03*
Y68898D03*
X89803Y76772D03*
Y68898D03*
X81929Y100394D03*
Y92520D03*
Y84646D03*
X89803Y100394D03*
Y92520D03*
Y84646D03*
X81929Y108268D03*
X89803D03*
G54D17*
X51900Y162300D03*
X53200Y169500D03*
X76900Y20200D03*
X65600Y160400D03*
X57200Y165300D03*
X73200Y162100D03*
X62200Y169900D03*
X70400Y170000D03*
X90200Y22400D03*
X94900Y144500D03*
X83800Y154500D03*
X99000Y148900D03*
X78800Y158000D03*
X93900Y162900D03*
X90200Y169500D03*
X81600Y162600D03*
X92600Y154800D03*
X100700Y163400D03*
X89000Y150200D03*
X88000Y158900D03*
X83500Y169700D03*
X78200Y169900D03*
X96900Y169500D03*
X98000Y157100D03*
X102500Y29400D03*
X107200Y19300D03*
X121200Y33900D03*
X102000Y141900D03*
X114000Y145200D03*
X119900Y143200D03*
X108600Y143100D03*
X111800Y151800D03*
X104900Y157400D03*
X120500Y157200D03*
X111900Y164800D03*
X118100Y162100D03*
X104500Y150300D03*
X110900Y159200D03*
X118400Y152000D03*
X106500Y170300D03*
X115300Y170200D03*
X123900Y41000D03*
X138700Y63500D03*
X144100Y72900D03*
X139800Y90200D03*
X131400Y91300D03*
X129200Y101300D03*
Y142400D03*
X126600Y149500D03*
X165600Y19400D03*
X168100Y48400D03*
X151500Y35800D03*
X159800Y65100D03*
X161800Y86800D03*
X158200Y102400D03*
X184100Y36600D03*
X174300Y73300D03*
X181400Y84700D03*
X194400Y20200D03*
X197800Y30900D03*
Y48000D03*
X214700Y35800D03*
X195600Y64100D03*
X206700Y72700D03*
X225800Y19600D03*
X229200Y30900D03*
X216400Y100500D03*
X254400Y19200D03*
X257800Y51200D03*
X244900Y36600D03*
X254400Y74300D03*
X251600Y100100D03*
X252200Y159400D03*
X252800Y179900D03*
X268300Y36200D03*
X283600Y69500D03*
X273300Y94900D03*
X281800Y100900D03*
X267700Y145200D03*
X280000Y159800D03*
X281000Y180700D03*
X307800Y101100D03*
X300300Y140000D03*
X350000Y161800D03*
X350200Y181100D03*
X813700Y43900D03*
X809700Y86500D03*
X839700D03*
X838300Y128100D03*
X855400Y152400D03*
X857000Y189800D03*
X869700Y86500D03*
X868300Y128100D03*
X899700Y86500D03*
X898300Y128100D03*
X885400Y152400D03*
X887000Y189800D03*
X929700Y86500D03*
X928300Y128100D03*
X915400Y152400D03*
X917000Y189800D03*
X945400Y152400D03*
X947000Y189800D03*
X959000Y18000D03*
X959700Y86500D03*
X958300Y128100D03*
X975400Y152400D03*
X989700Y86500D03*
X988300Y128100D03*
X977000Y189800D03*
X1018300Y128100D03*
X1005400Y152400D03*
X1007000Y189800D03*
X1043000Y45500D03*
X1031900Y84100D03*
X1035400Y152400D03*
X1037000Y189800D03*
X1063700Y15300D03*
X1061900Y84100D03*
X1048300Y128100D03*
X1065400Y152400D03*
X1067000Y189800D03*
X1073000Y45500D03*
X1078300Y128100D03*
X1091900Y84100D03*
X1108300Y128100D03*
X1095400Y152400D03*
X1097000Y189800D03*
X1120900Y64500D03*
X1121900Y84100D03*
X1125400Y152400D03*
X1127000Y189800D03*
X1147100Y64500D03*
X1151900Y84100D03*
X1155400Y152400D03*
X1157000Y189800D03*
G54D26*
X367402Y11810D03*
Y19684D03*
Y27558D03*
X359528Y11810D03*
Y19684D03*
Y27558D03*
X367402Y43306D03*
Y51180D03*
X359528Y43306D03*
Y51180D03*
X367402Y59054D03*
X359528D03*
X1229606Y11810D03*
Y19684D03*
Y27558D03*
Y43306D03*
Y51180D03*
Y59054D03*
X1237480Y11810D03*
Y19684D03*
Y27558D03*
Y43306D03*
Y51180D03*
Y59054D03*
G54D15*
X44528Y41339D03*
Y53150D03*
Y64961D03*
Y76772D03*
Y88583D03*
Y100394D03*
Y112205D03*
Y124016D03*
G54D33*
X452875Y131650D03*
X455867Y153658D03*
X452875Y194642D03*
X516851Y140666D03*
X519843Y115666D03*
Y194642D03*
X1322954Y131650D03*
Y194642D03*
X1325946Y153658D03*
X1389922Y115666D03*
X1386930Y140666D03*
X1389922Y194642D03*
G54D25*
X351654Y37400D03*
X1221732D03*
G54D12*
X17717Y18504D03*
X1670512D03*
G54D35*
X639283Y108622D03*
Y167677D03*
X793693Y108622D03*
Y167677D03*
X1509362Y108622D03*
Y167677D03*
X1663772Y108622D03*
Y167677D03*
G54D34*
X463859Y176650D03*
X508859D03*
X1333938D03*
X1378938D03*
G54D13*
X17716Y114173D03*
X314213Y163386D03*
X783661Y18504D03*
X826024Y163386D03*
X1101615Y18504D03*
X1184292Y163386D03*
G54D30*
X430591Y56653D03*
X579883Y56654D03*
X1300670D03*
X1449962Y56653D03*
G54D23*
X306772Y19685D03*
Y41850D03*
Y67913D03*
X612047Y19685D03*
Y41850D03*
Y67913D03*
X1176851Y19685D03*
Y41850D03*
Y67913D03*
X1482126Y19685D03*
Y41850D03*
Y67913D03*
G54D18*
X64500Y165200D03*
X89400Y165300D03*
X122758Y82442D03*
X117158Y82542D03*
X112158Y82342D03*
X106958Y82142D03*
X105800Y165400D03*
X125558Y79642D03*
X526612Y142000D03*
%LPC*%
G75*
G54D37*
G01X457212Y-338900D02*
Y-343900D01*
G01X455755Y-338900D02*
X458669D01*
G01X463579Y-343900D02*
X461045D01*
Y-338900D01*
X463579D01*
G01X462565Y-341317D02*
X461045D01*
G01X466145Y-338900D02*
Y-343900D01*
X468679D01*
G01X472512Y-344067D02*
X472385Y-343983D01*
Y-343817D01*
X472512Y-343733D01*
X472639Y-343817D01*
Y-343983D01*
X472512Y-344067D01*
G01Y-341817D02*
X472385Y-341733D01*
Y-341567D01*
X472512Y-341483D01*
X472639Y-341567D01*
Y-341733D01*
X472512Y-341817D01*
G01X477295Y-345567D02*
X476662Y-344733D01*
X476345Y-343900D01*
Y-340567D01*
X476662Y-339733D01*
X477295Y-338900D01*
G01X482712D02*
X482205Y-339067D01*
X481825Y-339483D01*
X481572Y-339983D01*
X481382Y-340650D01*
X481319Y-341400D01*
X481382Y-342150D01*
X481572Y-342817D01*
X481825Y-343317D01*
X482205Y-343733D01*
X482712Y-343900D01*
X483219Y-343733D01*
X483599Y-343317D01*
X483852Y-342817D01*
X484042Y-342150D01*
X484105Y-341400D01*
X484042Y-340650D01*
X483852Y-339983D01*
X483599Y-339483D01*
X483219Y-339067D01*
X482712Y-338900D01*
G01X486419Y-342900D02*
X486799Y-343483D01*
X487305Y-343817D01*
X487875Y-343900D01*
X488382Y-343817D01*
X488889Y-343400D01*
X489205Y-342900D01*
X489269Y-342400D01*
X489142Y-341817D01*
X488699Y-341400D01*
X488255Y-341233D01*
X487685D01*
G01X488255D02*
X488635Y-340983D01*
X488952Y-340567D01*
X489079Y-340067D01*
X488952Y-339567D01*
X488635Y-339150D01*
X488065Y-338900D01*
X487495Y-338983D01*
X486925Y-339317D01*
G01X493229Y-345567D02*
X493862Y-344733D01*
X494179Y-343900D01*
Y-340567D01*
X493862Y-339733D01*
X493229Y-338900D01*
G01X496619Y-342900D02*
X496999Y-343483D01*
X497505Y-343817D01*
X498075Y-343900D01*
X498582Y-343817D01*
X499089Y-343400D01*
X499405Y-342900D01*
X499469Y-342400D01*
X499342Y-341817D01*
X498899Y-341400D01*
X498455Y-341233D01*
X497885D01*
G01X498455D02*
X498835Y-340983D01*
X499152Y-340567D01*
X499279Y-340067D01*
X499152Y-339567D01*
X498835Y-339150D01*
X498265Y-338900D01*
X497695Y-338983D01*
X497125Y-339317D01*
G01X501909Y-339733D02*
X502289Y-339233D01*
X502732Y-338983D01*
X503239Y-338900D01*
X503872Y-339067D01*
X504315Y-339483D01*
X504442Y-339983D01*
X504379Y-340483D01*
X504125Y-340900D01*
X502859Y-341733D01*
X502289Y-342317D01*
X501909Y-343150D01*
X501782Y-343900D01*
X504442D01*
G01X508085D02*
X508212Y-342817D01*
X508402Y-341900D01*
X508655Y-341067D01*
X508972Y-340150D01*
X509479Y-338900D01*
X506945D01*
G01X512489Y-342233D02*
X514135D01*
G01X517209Y-339733D02*
X517589Y-339233D01*
X518032Y-338983D01*
X518539Y-338900D01*
X519172Y-339067D01*
X519615Y-339483D01*
X519742Y-339983D01*
X519679Y-340483D01*
X519425Y-340900D01*
X518159Y-341733D01*
X517589Y-342317D01*
X517209Y-343150D01*
X517082Y-343900D01*
X519742D01*
G01X522119Y-342900D02*
X522499Y-343483D01*
X523005Y-343817D01*
X523575Y-343900D01*
X524082Y-343817D01*
X524589Y-343400D01*
X524905Y-342900D01*
X524969Y-342400D01*
X524842Y-341817D01*
X524399Y-341400D01*
X523955Y-341233D01*
X523385D01*
G01X523955D02*
X524335Y-340983D01*
X524652Y-340567D01*
X524779Y-340067D01*
X524652Y-339567D01*
X524335Y-339150D01*
X523765Y-338900D01*
X523195Y-338983D01*
X522625Y-339317D01*
G01X529372Y-343900D02*
Y-338900D01*
X527029Y-342483D01*
X530195D01*
G01X532319Y-343150D02*
X532699Y-343567D01*
X533142Y-343817D01*
X533712Y-343900D01*
X534282Y-343733D01*
X534725Y-343400D01*
X535042Y-342817D01*
X535105Y-342150D01*
X534979Y-341483D01*
X534662Y-341067D01*
X534219Y-340733D01*
X533775Y-340650D01*
X533332Y-340733D01*
X532762Y-341067D01*
X532952Y-338900D01*
X534662D01*
G01X542709Y-343900D02*
Y-338900D01*
X545115D01*
G01X544229Y-341317D02*
X542709D01*
G01X547429Y-343900D02*
X549012Y-338900D01*
X550595Y-343900D01*
G01X550025Y-342150D02*
X547999D01*
G01X552782Y-343900D02*
X555442Y-338900D01*
G01X552782D02*
X555442Y-343900D01*
G01X559212Y-344067D02*
X559085Y-343983D01*
Y-343817D01*
X559212Y-343733D01*
X559339Y-343817D01*
Y-343983D01*
X559212Y-344067D01*
G01Y-341817D02*
X559085Y-341733D01*
Y-341567D01*
X559212Y-341483D01*
X559339Y-341567D01*
Y-341733D01*
X559212Y-341817D01*
G01X563995Y-345567D02*
X563362Y-344733D01*
X563045Y-343900D01*
Y-340567D01*
X563362Y-339733D01*
X563995Y-338900D01*
G01X569412D02*
X568905Y-339067D01*
X568525Y-339483D01*
X568272Y-339983D01*
X568082Y-340650D01*
X568019Y-341400D01*
X568082Y-342150D01*
X568272Y-342817D01*
X568525Y-343317D01*
X568905Y-343733D01*
X569412Y-343900D01*
X569919Y-343733D01*
X570299Y-343317D01*
X570552Y-342817D01*
X570742Y-342150D01*
X570805Y-341400D01*
X570742Y-340650D01*
X570552Y-339983D01*
X570299Y-339483D01*
X569919Y-339067D01*
X569412Y-338900D01*
G01X573119Y-342900D02*
X573499Y-343483D01*
X574005Y-343817D01*
X574575Y-343900D01*
X575082Y-343817D01*
X575589Y-343400D01*
X575905Y-342900D01*
X575969Y-342400D01*
X575842Y-341817D01*
X575399Y-341400D01*
X574955Y-341233D01*
X574385D01*
G01X574955D02*
X575335Y-340983D01*
X575652Y-340567D01*
X575779Y-340067D01*
X575652Y-339567D01*
X575335Y-339150D01*
X574765Y-338900D01*
X574195Y-338983D01*
X573625Y-339317D01*
G01X579929Y-345567D02*
X580562Y-344733D01*
X580879Y-343900D01*
Y-340567D01*
X580562Y-339733D01*
X579929Y-338900D01*
G01X583319Y-342900D02*
X583699Y-343483D01*
X584205Y-343817D01*
X584775Y-343900D01*
X585282Y-343817D01*
X585789Y-343400D01*
X586105Y-342900D01*
X586169Y-342400D01*
X586042Y-341817D01*
X585599Y-341400D01*
X585155Y-341233D01*
X584585D01*
G01X585155D02*
X585535Y-340983D01*
X585852Y-340567D01*
X585979Y-340067D01*
X585852Y-339567D01*
X585535Y-339150D01*
X584965Y-338900D01*
X584395Y-338983D01*
X583825Y-339317D01*
G01X588735Y-343317D02*
X589179Y-343733D01*
X589685Y-343900D01*
X590192Y-343733D01*
X590635Y-343233D01*
X590952Y-342483D01*
X591079Y-341733D01*
Y-340817D01*
X590952Y-340067D01*
X590635Y-339400D01*
X590255Y-339067D01*
X589812Y-338900D01*
X589305Y-339067D01*
X588925Y-339400D01*
X588672Y-339900D01*
X588545Y-340567D01*
X588672Y-341150D01*
X588989Y-341733D01*
X589369Y-342067D01*
X589812Y-342150D01*
X590319Y-341983D01*
X590699Y-341567D01*
X591079Y-340817D01*
G01X594785Y-343900D02*
X594912Y-342817D01*
X595102Y-341900D01*
X595355Y-341067D01*
X595672Y-340150D01*
X596179Y-338900D01*
X593645D01*
G01X599189Y-342233D02*
X600835D01*
G01X603719Y-342900D02*
X604099Y-343483D01*
X604605Y-343817D01*
X605175Y-343900D01*
X605682Y-343817D01*
X606189Y-343400D01*
X606505Y-342900D01*
X606569Y-342400D01*
X606442Y-341817D01*
X605999Y-341400D01*
X605555Y-341233D01*
X604985D01*
G01X605555D02*
X605935Y-340983D01*
X606252Y-340567D01*
X606379Y-340067D01*
X606252Y-339567D01*
X605935Y-339150D01*
X605365Y-338900D01*
X604795Y-338983D01*
X604225Y-339317D01*
G01X609009Y-341817D02*
X609452Y-341233D01*
X609832Y-340900D01*
X610339Y-340733D01*
X610782Y-340900D01*
X611099Y-341233D01*
X611352Y-341733D01*
X611415Y-342317D01*
X611352Y-342817D01*
X611099Y-343317D01*
X610719Y-343733D01*
X610275Y-343900D01*
X609769Y-343733D01*
X609325Y-343233D01*
X609072Y-342483D01*
X609009Y-341650D01*
X609135Y-340567D01*
X609325Y-339983D01*
X609642Y-339400D01*
X610085Y-338983D01*
X610529Y-338900D01*
X610972Y-339067D01*
X611289Y-339483D01*
G01X615312Y-343900D02*
Y-338900D01*
X614552Y-339900D01*
G01Y-343900D02*
X616072D01*
G01X621172D02*
Y-338900D01*
X618829Y-342483D01*
X621995D01*
G01X445212Y-273900D02*
Y-348900D01*
X945212D01*
Y-273900D01*
X445212D01*
G01X640212D02*
Y-348900D01*
G01Y-323900D02*
X743212D01*
Y-298900D01*
G01X640212D02*
X743212D01*
G01Y-273900D02*
Y-348900D01*
G01X745212Y-273900D02*
Y-348900D01*
G01X750719Y-333900D02*
Y-328900D01*
X751985D01*
X752492Y-329150D01*
X752872Y-329483D01*
X753189Y-329983D01*
X753442Y-330567D01*
X753505Y-331400D01*
X753442Y-332233D01*
X753189Y-332817D01*
X752872Y-333317D01*
X752492Y-333650D01*
X751985Y-333900D01*
X750719D01*
G01X755629D02*
X757212Y-328900D01*
X758795Y-333900D01*
G01X758225Y-332150D02*
X756199D01*
G01X762312Y-328900D02*
Y-333900D01*
G01X760855Y-328900D02*
X763769D01*
G01X768679Y-333900D02*
X766145D01*
Y-328900D01*
X768679D01*
G01X767665Y-331317D02*
X766145D01*
G01X772512Y-334067D02*
X772385Y-333983D01*
Y-333817D01*
X772512Y-333733D01*
X772639Y-333817D01*
Y-333983D01*
X772512Y-334067D01*
G01Y-331817D02*
X772385Y-331733D01*
Y-331567D01*
X772512Y-331483D01*
X772639Y-331567D01*
Y-331733D01*
X772512Y-331817D01*
G01X745212Y-323900D02*
X945212D01*
G01X750845Y-308900D02*
Y-303900D01*
X752365D01*
X752872Y-304150D01*
X753252Y-304733D01*
X753379Y-305400D01*
X753252Y-306067D01*
X752935Y-306567D01*
X752365Y-306817D01*
X750845D01*
G01X756072Y-309067D02*
X758352Y-303900D01*
G01X760855Y-308900D02*
Y-303900D01*
X763769Y-308900D01*
Y-303900D01*
G01X767412Y-309067D02*
X767285Y-308983D01*
Y-308817D01*
X767412Y-308733D01*
X767539Y-308817D01*
Y-308983D01*
X767412Y-309067D01*
G01Y-306817D02*
X767285Y-306733D01*
Y-306567D01*
X767412Y-306483D01*
X767539Y-306567D01*
Y-306733D01*
X767412Y-306817D01*
G01X745212Y-298900D02*
X945212D01*
G01X750845Y-283900D02*
Y-278900D01*
X752365D01*
X752872Y-279150D01*
X753252Y-279733D01*
X753379Y-280400D01*
X753252Y-281067D01*
X752935Y-281567D01*
X752365Y-281817D01*
X750845D01*
G01X755945Y-283900D02*
Y-278900D01*
X757529D01*
X758035Y-279150D01*
X758352Y-279483D01*
X758479Y-280150D01*
X758352Y-280817D01*
X757972Y-281233D01*
X757529Y-281483D01*
X755945D01*
G01X757529D02*
X758479Y-283900D01*
G01X762312D02*
X761805Y-283817D01*
X761362Y-283483D01*
X760982Y-282983D01*
X760729Y-282400D01*
X760602Y-281733D01*
Y-281067D01*
X760729Y-280400D01*
X760982Y-279817D01*
X761362Y-279317D01*
X761805Y-278983D01*
X762312Y-278900D01*
X762819Y-278983D01*
X763262Y-279317D01*
X763642Y-279817D01*
X763895Y-280400D01*
X764022Y-281067D01*
Y-281733D01*
X763895Y-282400D01*
X763642Y-282983D01*
X763262Y-283483D01*
X762819Y-283817D01*
X762312Y-283900D01*
G01X766145Y-282900D02*
X766462Y-283400D01*
X766842Y-283733D01*
X767285Y-283900D01*
X767792Y-283733D01*
X768172Y-283400D01*
X768552Y-282900D01*
X768679Y-282233D01*
Y-278900D01*
G01X773779Y-283900D02*
X771245D01*
Y-278900D01*
X773779D01*
G01X772765Y-281317D02*
X771245D01*
G01X779005Y-279317D02*
X778625Y-279067D01*
X778182Y-278900D01*
X777675D01*
X777105Y-279150D01*
X776662Y-279567D01*
X776345Y-280067D01*
X776092Y-280900D01*
X776029Y-281650D01*
X776155Y-282400D01*
X776345Y-282900D01*
X776725Y-283400D01*
X777169Y-283733D01*
X777612Y-283900D01*
X778055D01*
X778499Y-283733D01*
X778879Y-283483D01*
X779195Y-283150D01*
G01X782712Y-278900D02*
Y-283900D01*
G01X781255Y-278900D02*
X784169D01*
G01X787812Y-284067D02*
X787685Y-283983D01*
Y-283817D01*
X787812Y-283733D01*
X787939Y-283817D01*
Y-283983D01*
X787812Y-284067D01*
G01Y-281817D02*
X787685Y-281733D01*
Y-281567D01*
X787812Y-281483D01*
X787939Y-281567D01*
Y-281733D01*
X787812Y-281817D01*
G01X860212Y-323900D02*
Y-348900D01*
G01X865845Y-333900D02*
Y-328900D01*
X867429D01*
X867935Y-329150D01*
X868252Y-329483D01*
X868379Y-330150D01*
X868252Y-330817D01*
X867872Y-331233D01*
X867429Y-331483D01*
X865845D01*
G01X867429D02*
X868379Y-333900D01*
G01X873479D02*
X870945D01*
Y-328900D01*
X873479D01*
G01X872465Y-331317D02*
X870945D01*
G01X875729Y-328900D02*
X877312Y-333900D01*
X878895Y-328900D01*
G01X882412Y-334067D02*
X882285Y-333983D01*
Y-333817D01*
X882412Y-333733D01*
X882539Y-333817D01*
Y-333983D01*
X882412Y-334067D01*
G01Y-331817D02*
X882285Y-331733D01*
Y-331567D01*
X882412Y-331483D01*
X882539Y-331567D01*
Y-331733D01*
X882412Y-331817D01*
G01X909212Y-323900D02*
Y-348900D01*
G01X-471400Y-391900D02*
Y1528800D01*
X2244200D01*
Y-391900D01*
X-471400D01*
G01X455917Y-335560D02*
X456544Y-336085D01*
X457249Y-336400D01*
X457875D01*
X458502Y-336085D01*
X458972Y-335560D01*
X459207Y-334825D01*
X459050Y-334090D01*
X458659Y-333460D01*
X457954Y-333040D01*
X457014Y-332830D01*
X456465Y-332410D01*
X456230Y-331675D01*
X456387Y-330940D01*
X456779Y-330415D01*
X457327Y-330100D01*
X457875D01*
X458424Y-330310D01*
X458894Y-330835D01*
G01X462217Y-336400D02*
Y-330100D01*
G01X465507D02*
Y-336400D01*
G01Y-333250D02*
X462217D01*
G01X469222Y-330100D02*
X471102D01*
G01X470162D02*
Y-336400D01*
G01X469222D02*
X471102D01*
G01X478029D02*
X474895D01*
Y-330100D01*
X478029D01*
G01X476775Y-333145D02*
X474895D01*
G01X480960Y-336400D02*
Y-330100D01*
X484564Y-336400D01*
Y-330100D01*
G01X488905Y-337555D02*
X489219Y-336190D01*
G01X495362Y-330100D02*
Y-336400D01*
G01X493560Y-330100D02*
X497164D01*
G01X499704Y-336400D02*
X501662Y-330100D01*
X503620Y-336400D01*
G01X502915Y-334195D02*
X500409D01*
G01X507022Y-330100D02*
X508902D01*
G01X507962D02*
Y-336400D01*
G01X507022D02*
X508902D01*
G01X511912Y-330100D02*
X513009Y-336400D01*
X514262Y-330100D01*
X515515Y-336400D01*
X516612Y-330100D01*
G01X518604Y-336400D02*
X520562Y-330100D01*
X522520Y-336400D01*
G01X521815Y-334195D02*
X519309D01*
G01X525060Y-336400D02*
Y-330100D01*
X528664Y-336400D01*
Y-330100D01*
G01X537895Y-336400D02*
Y-330100D01*
X539854D01*
X540480Y-330415D01*
X540872Y-330835D01*
X541029Y-331675D01*
X540872Y-332515D01*
X540402Y-333040D01*
X539854Y-333355D01*
X537895D01*
G01X539854D02*
X541029Y-336400D01*
G01X545762Y-336610D02*
X545605Y-336505D01*
Y-336295D01*
X545762Y-336190D01*
X545919Y-336295D01*
Y-336505D01*
X545762Y-336610D01*
G01X552062Y-336400D02*
X551435Y-336295D01*
X550887Y-335875D01*
X550417Y-335245D01*
X550104Y-334510D01*
X549947Y-333670D01*
Y-332830D01*
X550104Y-331990D01*
X550417Y-331255D01*
X550887Y-330625D01*
X551435Y-330205D01*
X552062Y-330100D01*
X552689Y-330205D01*
X553237Y-330625D01*
X553707Y-331255D01*
X554020Y-331990D01*
X554177Y-332830D01*
Y-333670D01*
X554020Y-334510D01*
X553707Y-335245D01*
X553237Y-335875D01*
X552689Y-336295D01*
X552062Y-336400D01*
G01X558362Y-336610D02*
X558205Y-336505D01*
Y-336295D01*
X558362Y-336190D01*
X558519Y-336295D01*
Y-336505D01*
X558362Y-336610D01*
G01X566385Y-330625D02*
X565915Y-330310D01*
X565367Y-330100D01*
X564740D01*
X564035Y-330415D01*
X563487Y-330940D01*
X563095Y-331570D01*
X562782Y-332620D01*
X562704Y-333565D01*
X562860Y-334510D01*
X563095Y-335140D01*
X563565Y-335770D01*
X564114Y-336190D01*
X564662Y-336400D01*
X565210D01*
X565759Y-336190D01*
X566229Y-335875D01*
X566620Y-335455D01*
G01X570962Y-336610D02*
X570805Y-336505D01*
Y-336295D01*
X570962Y-336190D01*
X571119Y-336295D01*
Y-336505D01*
X570962Y-336610D01*
G01X455839Y-326400D02*
Y-320100D01*
G01X458815D02*
X455839Y-323985D01*
G01X459285Y-326400D02*
X457170Y-322200D01*
G01X462139Y-320100D02*
Y-324615D01*
X462452Y-325560D01*
X463079Y-326190D01*
X463862Y-326400D01*
X464645Y-326190D01*
X465272Y-325560D01*
X465585Y-324615D01*
Y-320100D01*
G01X471729Y-326400D02*
X468595D01*
Y-320100D01*
X471729D01*
G01X470475Y-323145D02*
X468595D01*
G01X475522Y-320100D02*
X477402D01*
G01X476462D02*
Y-326400D01*
G01X475522D02*
X477402D01*
G01X487417Y-325560D02*
X488044Y-326085D01*
X488749Y-326400D01*
X489375D01*
X490002Y-326085D01*
X490472Y-325560D01*
X490707Y-324825D01*
X490550Y-324090D01*
X490159Y-323460D01*
X489454Y-323040D01*
X488514Y-322830D01*
X487965Y-322410D01*
X487730Y-321675D01*
X487887Y-320940D01*
X488279Y-320415D01*
X488827Y-320100D01*
X489375D01*
X489924Y-320310D01*
X490394Y-320835D01*
G01X493717Y-326400D02*
Y-320100D01*
G01X497007D02*
Y-326400D01*
G01Y-323250D02*
X493717D01*
G01X499704Y-326400D02*
X501662Y-320100D01*
X503620Y-326400D01*
G01X502915Y-324195D02*
X500409D01*
G01X506160Y-326400D02*
Y-320100D01*
X509764Y-326400D01*
Y-320100D01*
G01X518917Y-326400D02*
Y-320100D01*
G01X522207D02*
Y-326400D01*
G01Y-323250D02*
X518917D01*
G01X525217Y-325560D02*
X525844Y-326085D01*
X526549Y-326400D01*
X527175D01*
X527802Y-326085D01*
X528272Y-325560D01*
X528507Y-324825D01*
X528350Y-324090D01*
X527959Y-323460D01*
X527254Y-323040D01*
X526314Y-322830D01*
X525765Y-322410D01*
X525530Y-321675D01*
X525687Y-320940D01*
X526079Y-320415D01*
X526627Y-320100D01*
X527175D01*
X527724Y-320310D01*
X528194Y-320835D01*
G01X532222Y-320100D02*
X534102D01*
G01X533162D02*
Y-326400D01*
G01X532222D02*
X534102D01*
G01X537504D02*
X539462Y-320100D01*
X541420Y-326400D01*
G01X540715Y-324195D02*
X538209D01*
G01X543960Y-326400D02*
Y-320100D01*
X547564Y-326400D01*
Y-320100D01*
G01X552532Y-323250D02*
X554099D01*
Y-325140D01*
X553629Y-325770D01*
X553080Y-326190D01*
X552297Y-326400D01*
X551514Y-326190D01*
X550965Y-325770D01*
X550495Y-325140D01*
X550182Y-324405D01*
X550025Y-323565D01*
Y-322830D01*
X550182Y-322200D01*
X550495Y-321465D01*
X550965Y-320835D01*
X551435Y-320415D01*
X552062Y-320100D01*
X552610D01*
X553237Y-320310D01*
X553707Y-320730D01*
G01X558205Y-327555D02*
X558519Y-326190D01*
G01X564662Y-320100D02*
Y-326400D01*
G01X562860Y-320100D02*
X566464D01*
G01X569004Y-326400D02*
X570962Y-320100D01*
X572920Y-326400D01*
G01X572215Y-324195D02*
X569709D01*
G01X577262Y-326400D02*
X576635Y-326295D01*
X576087Y-325875D01*
X575617Y-325245D01*
X575304Y-324510D01*
X575147Y-323670D01*
Y-322830D01*
X575304Y-321990D01*
X575617Y-321255D01*
X576087Y-320625D01*
X576635Y-320205D01*
X577262Y-320100D01*
X577889Y-320205D01*
X578437Y-320625D01*
X578907Y-321255D01*
X579220Y-321990D01*
X579377Y-322830D01*
Y-323670D01*
X579220Y-324510D01*
X578907Y-325245D01*
X578437Y-325875D01*
X577889Y-326295D01*
X577262Y-326400D01*
G01X589862D02*
Y-323565D01*
X588295Y-320100D01*
G01X591429D02*
X589862Y-323565D01*
G01X594439Y-320100D02*
Y-324615D01*
X594752Y-325560D01*
X595379Y-326190D01*
X596162Y-326400D01*
X596945Y-326190D01*
X597572Y-325560D01*
X597885Y-324615D01*
Y-320100D01*
G01X600504Y-326400D02*
X602462Y-320100D01*
X604420Y-326400D01*
G01X603715Y-324195D02*
X601209D01*
G01X606960Y-326400D02*
Y-320100D01*
X610564Y-326400D01*
Y-320100D01*
G01X455760Y-316400D02*
Y-310100D01*
X459364Y-316400D01*
Y-310100D01*
G01X463862Y-316400D02*
X463235Y-316295D01*
X462687Y-315875D01*
X462217Y-315245D01*
X461904Y-314510D01*
X461747Y-313670D01*
Y-312830D01*
X461904Y-311990D01*
X462217Y-311255D01*
X462687Y-310625D01*
X463235Y-310205D01*
X463862Y-310100D01*
X464489Y-310205D01*
X465037Y-310625D01*
X465507Y-311255D01*
X465820Y-311990D01*
X465977Y-312830D01*
Y-313670D01*
X465820Y-314510D01*
X465507Y-315245D01*
X465037Y-315875D01*
X464489Y-316295D01*
X463862Y-316400D01*
G01X470162Y-316610D02*
X470005Y-316505D01*
Y-316295D01*
X470162Y-316190D01*
X470319Y-316295D01*
Y-316505D01*
X470162Y-316610D01*
G01X476462Y-316400D02*
Y-310100D01*
X475522Y-311360D01*
G01Y-316400D02*
X477402D01*
G01X482762D02*
X483310Y-316295D01*
X483937Y-315980D01*
X484329Y-315455D01*
X484485Y-314720D01*
X484329Y-313985D01*
X483859Y-313355D01*
X483154Y-313040D01*
X482370D01*
X481900Y-312830D01*
X481509Y-312305D01*
X481352Y-311570D01*
X481587Y-310835D01*
X482135Y-310310D01*
X482762Y-310100D01*
X483389Y-310310D01*
X483937Y-310835D01*
X484172Y-311570D01*
X484015Y-312305D01*
X483624Y-312830D01*
X483154Y-313040D01*
X482370D01*
X481665Y-313355D01*
X481195Y-313985D01*
X481039Y-314720D01*
X481195Y-315455D01*
X481587Y-315980D01*
X482214Y-316295D01*
X482762Y-316400D01*
G01X489062D02*
X489610Y-316295D01*
X490237Y-315980D01*
X490629Y-315455D01*
X490785Y-314720D01*
X490629Y-313985D01*
X490159Y-313355D01*
X489454Y-313040D01*
X488670D01*
X488200Y-312830D01*
X487809Y-312305D01*
X487652Y-311570D01*
X487887Y-310835D01*
X488435Y-310310D01*
X489062Y-310100D01*
X489689Y-310310D01*
X490237Y-310835D01*
X490472Y-311570D01*
X490315Y-312305D01*
X489924Y-312830D01*
X489454Y-313040D01*
X488670D01*
X487965Y-313355D01*
X487495Y-313985D01*
X487339Y-314720D01*
X487495Y-315455D01*
X487887Y-315980D01*
X488514Y-316295D01*
X489062Y-316400D01*
G01X495205Y-317555D02*
X495519Y-316190D01*
G01X499312Y-310100D02*
X500409Y-316400D01*
X501662Y-310100D01*
X502915Y-316400D01*
X504012Y-310100D01*
G01X509529Y-316400D02*
X506395D01*
Y-310100D01*
X509529D01*
G01X508275Y-313145D02*
X506395D01*
G01X512460Y-316400D02*
Y-310100D01*
X516064Y-316400D01*
Y-310100D01*
G01X525217Y-316400D02*
Y-310100D01*
G01X528507D02*
Y-316400D01*
G01Y-313250D02*
X525217D01*
G01X530812Y-310100D02*
X531909Y-316400D01*
X533162Y-310100D01*
X534415Y-316400D01*
X535512Y-310100D01*
G01X537504Y-316400D02*
X539462Y-310100D01*
X541420Y-316400D01*
G01X540715Y-314195D02*
X538209D01*
G01X550574Y-311150D02*
X551044Y-310520D01*
X551592Y-310205D01*
X552219Y-310100D01*
X553002Y-310310D01*
X553550Y-310835D01*
X553707Y-311465D01*
X553629Y-312095D01*
X553315Y-312620D01*
X551749Y-313670D01*
X551044Y-314405D01*
X550574Y-315455D01*
X550417Y-316400D01*
X553707D01*
G01X556560D02*
Y-310100D01*
X560164Y-316400D01*
Y-310100D01*
G01X562939Y-316400D02*
Y-310100D01*
X564505D01*
X565132Y-310415D01*
X565602Y-310835D01*
X565994Y-311465D01*
X566307Y-312200D01*
X566385Y-313250D01*
X566307Y-314300D01*
X565994Y-315035D01*
X565602Y-315665D01*
X565132Y-316085D01*
X564505Y-316400D01*
X562939D01*
G01X575695D02*
Y-310100D01*
X577654D01*
X578280Y-310415D01*
X578672Y-310835D01*
X578829Y-311675D01*
X578672Y-312515D01*
X578202Y-313040D01*
X577654Y-313355D01*
X575695D01*
G01X577654D02*
X578829Y-316400D01*
G01X581839D02*
Y-310100D01*
X583405D01*
X584032Y-310415D01*
X584502Y-310835D01*
X584894Y-311465D01*
X585207Y-312200D01*
X585285Y-313250D01*
X585207Y-314300D01*
X584894Y-315035D01*
X584502Y-315665D01*
X584032Y-316085D01*
X583405Y-316400D01*
X581839D01*
G01X589862Y-316610D02*
X589705Y-316505D01*
Y-316295D01*
X589862Y-316190D01*
X590019Y-316295D01*
Y-316505D01*
X589862Y-316610D01*
G01X479862Y-303700D02*
X477342Y-303283D01*
X475137Y-301617D01*
X473247Y-299117D01*
X471987Y-296200D01*
X471357Y-292867D01*
Y-289533D01*
X471987Y-286200D01*
X473247Y-283283D01*
X475137Y-280784D01*
X477342Y-279117D01*
X479862Y-278700D01*
X482382Y-279117D01*
X484587Y-280784D01*
X486477Y-283283D01*
X487737Y-286200D01*
X488367Y-289533D01*
Y-292867D01*
X487737Y-296200D01*
X486477Y-299117D01*
X484587Y-301617D01*
X482382Y-303283D01*
X479862Y-303700D01*
G01X482382Y-297033D02*
X486162Y-303700D01*
G01X499707Y-287034D02*
Y-298700D01*
X500967Y-301617D01*
X502857Y-303283D01*
X505062Y-303700D01*
X507267Y-303283D01*
X509157Y-301617D01*
X510417Y-298700D01*
G01Y-303700D02*
Y-287034D01*
G01X535932Y-303700D02*
Y-287034D01*
G01Y-289950D02*
X534672Y-288284D01*
X532782Y-287450D01*
X530577Y-287034D01*
X528372Y-287867D01*
X526482Y-289533D01*
X525222Y-292034D01*
X524592Y-295367D01*
X525222Y-298700D01*
X526482Y-301201D01*
X528372Y-302867D01*
X530577Y-303700D01*
X532782Y-303283D01*
X534672Y-302034D01*
X535932Y-300367D01*
G01X550107Y-303700D02*
Y-287034D01*
G01Y-291200D02*
X551367Y-289117D01*
X553257Y-287450D01*
X555777Y-287034D01*
X557982Y-287450D01*
X559872Y-289117D01*
X560817Y-292034D01*
Y-303700D01*
G01X580662Y-278700D02*
Y-303700D01*
G01X576252Y-287034D02*
X585072D01*
G01X611532Y-303700D02*
Y-287034D01*
G01Y-289950D02*
X610272Y-288284D01*
X608382Y-287450D01*
X606177Y-287034D01*
X603972Y-287867D01*
X602082Y-289533D01*
X600822Y-292034D01*
X600192Y-295367D01*
X600822Y-298700D01*
X602082Y-301201D01*
X603972Y-302867D01*
X606177Y-303700D01*
X608382Y-303283D01*
X610272Y-302034D01*
X611532Y-300367D01*
G01X651212Y-283400D02*
Y-291400D01*
X655212D01*
G01X663012D02*
Y-286067D01*
G01Y-287000D02*
X662612Y-286467D01*
X662012Y-286200D01*
X661312Y-286067D01*
X660612Y-286333D01*
X660012Y-286867D01*
X659612Y-287667D01*
X659412Y-288733D01*
X659612Y-289800D01*
X660012Y-290600D01*
X660612Y-291133D01*
X661312Y-291400D01*
X662012Y-291267D01*
X662612Y-290867D01*
X663012Y-290334D01*
G01X667112Y-293800D02*
X667712Y-294067D01*
X668512Y-293800D01*
X669012Y-293267D01*
X669412Y-292600D01*
X670012Y-290467D01*
X671312Y-286067D01*
G01X668112D02*
X670012Y-290467D01*
G01X675712Y-287800D02*
X678912D01*
X678612Y-286867D01*
X678112Y-286333D01*
X677412Y-286067D01*
X676712Y-286200D01*
X676112Y-286600D01*
X675712Y-287533D01*
X675512Y-288334D01*
Y-289133D01*
X675712Y-289933D01*
X676212Y-290733D01*
X676812Y-291267D01*
X677512Y-291400D01*
X678212Y-291133D01*
X678912Y-290334D01*
G01X683812Y-291400D02*
Y-286067D01*
G01Y-287133D02*
X684312Y-286600D01*
X684812Y-286200D01*
X685512Y-286067D01*
X686012Y-286200D01*
X686612Y-286600D01*
G01X673512Y-333400D02*
X675912D01*
G01X674712D02*
Y-341400D01*
G01X673512D02*
X675912D01*
G01X681312D02*
Y-336067D01*
G01Y-337133D02*
X681812Y-336600D01*
X682312Y-336200D01*
X683012Y-336067D01*
X683512Y-336200D01*
X684112Y-336600D01*
G01X689212Y-337800D02*
X692412D01*
X692112Y-336867D01*
X691612Y-336333D01*
X690912Y-336067D01*
X690212Y-336200D01*
X689612Y-336600D01*
X689212Y-337533D01*
X689012Y-338334D01*
Y-339133D01*
X689212Y-339933D01*
X689712Y-340733D01*
X690312Y-341267D01*
X691012Y-341400D01*
X691712Y-341133D01*
X692412Y-340334D01*
G01X697012Y-341400D02*
Y-336067D01*
G01Y-337400D02*
X697412Y-336733D01*
X698012Y-336200D01*
X698812Y-336067D01*
X699512Y-336200D01*
X700112Y-336733D01*
X700412Y-337667D01*
Y-341400D01*
G01X705212Y-337800D02*
X708412D01*
X708112Y-336867D01*
X707612Y-336333D01*
X706912Y-336067D01*
X706212Y-336200D01*
X705612Y-336600D01*
X705212Y-337533D01*
X705012Y-338334D01*
Y-339133D01*
X705212Y-339933D01*
X705712Y-340733D01*
X706312Y-341267D01*
X707012Y-341400D01*
X707712Y-341133D01*
X708412Y-340334D01*
G01X679712Y-308400D02*
X682212Y-316400D01*
X684712Y-308400D01*
G01X692412Y-309067D02*
X691812Y-308667D01*
X691112Y-308400D01*
X690312D01*
X689412Y-308800D01*
X688712Y-309467D01*
X688212Y-310267D01*
X687812Y-311600D01*
X687712Y-312800D01*
X687912Y-314000D01*
X688212Y-314800D01*
X688812Y-315600D01*
X689512Y-316133D01*
X690212Y-316400D01*
X690912D01*
X691612Y-316133D01*
X692212Y-315733D01*
X692712Y-315200D01*
G01X700412Y-309067D02*
X699812Y-308667D01*
X699112Y-308400D01*
X698312D01*
X697412Y-308800D01*
X696712Y-309467D01*
X696212Y-310267D01*
X695812Y-311600D01*
X695712Y-312800D01*
X695912Y-314000D01*
X696212Y-314800D01*
X696812Y-315600D01*
X697512Y-316133D01*
X698212Y-316400D01*
X698912D01*
X699612Y-316133D01*
X700212Y-315733D01*
X700712Y-315200D01*
G01X705912Y-291400D02*
Y-283400D01*
X702212Y-289133D01*
X707212D01*
G01X777812Y-334733D02*
X778412Y-333933D01*
X779112Y-333533D01*
X779912Y-333400D01*
X780912Y-333667D01*
X781612Y-334333D01*
X781812Y-335133D01*
X781712Y-335934D01*
X781312Y-336600D01*
X779312Y-337933D01*
X778412Y-338867D01*
X777812Y-340200D01*
X777612Y-341400D01*
X781812D01*
G01X787712Y-333400D02*
X786912Y-333667D01*
X786312Y-334333D01*
X785912Y-335133D01*
X785612Y-336200D01*
X785512Y-337400D01*
X785612Y-338600D01*
X785912Y-339667D01*
X786312Y-340467D01*
X786912Y-341133D01*
X787712Y-341400D01*
X788512Y-341133D01*
X789112Y-340467D01*
X789512Y-339667D01*
X789812Y-338600D01*
X789912Y-337400D01*
X789812Y-336200D01*
X789512Y-335133D01*
X789112Y-334333D01*
X788512Y-333667D01*
X787712Y-333400D01*
G01X795712Y-341400D02*
Y-333400D01*
X794512Y-335000D01*
G01Y-341400D02*
X796912D01*
G01X801812Y-334733D02*
X802412Y-333933D01*
X803112Y-333533D01*
X803912Y-333400D01*
X804912Y-333667D01*
X805612Y-334333D01*
X805812Y-335133D01*
X805712Y-335934D01*
X805312Y-336600D01*
X803312Y-337933D01*
X802412Y-338867D01*
X801812Y-340200D01*
X801612Y-341400D01*
X805812D01*
G01X809912Y-341667D02*
X813512Y-333400D01*
G01X819712Y-341400D02*
Y-333400D01*
X818512Y-335000D01*
G01Y-341400D02*
X820912D01*
G01X827712Y-333400D02*
X826912Y-333667D01*
X826312Y-334333D01*
X825912Y-335133D01*
X825612Y-336200D01*
X825512Y-337400D01*
X825612Y-338600D01*
X825912Y-339667D01*
X826312Y-340467D01*
X826912Y-341133D01*
X827712Y-341400D01*
X828512Y-341133D01*
X829112Y-340467D01*
X829512Y-339667D01*
X829812Y-338600D01*
X829912Y-337400D01*
X829812Y-336200D01*
X829512Y-335133D01*
X829112Y-334333D01*
X828512Y-333667D01*
X827712Y-333400D01*
G01X833912Y-341667D02*
X837512Y-333400D01*
G01X841512Y-339800D02*
X842112Y-340733D01*
X842912Y-341267D01*
X843812Y-341400D01*
X844612Y-341267D01*
X845412Y-340600D01*
X845912Y-339800D01*
X846012Y-339000D01*
X845812Y-338067D01*
X845112Y-337400D01*
X844412Y-337133D01*
X843512D01*
G01X844412D02*
X845012Y-336733D01*
X845512Y-336067D01*
X845712Y-335267D01*
X845512Y-334467D01*
X845012Y-333800D01*
X844112Y-333400D01*
X843212Y-333533D01*
X842312Y-334067D01*
G01X851712Y-341400D02*
Y-333400D01*
X850512Y-335000D01*
G01Y-341400D02*
X852912D01*
G01X777512Y-316400D02*
Y-308400D01*
X779512D01*
X780312Y-308800D01*
X780912Y-309333D01*
X781412Y-310133D01*
X781812Y-311067D01*
X781912Y-312400D01*
X781812Y-313733D01*
X781412Y-314667D01*
X780912Y-315467D01*
X780312Y-316000D01*
X779512Y-316400D01*
X777512D01*
G01X785212D02*
X787712Y-308400D01*
X790212Y-316400D01*
G01X789312Y-313600D02*
X786112D01*
G01X795712Y-308400D02*
X794912Y-308667D01*
X794312Y-309333D01*
X793912Y-310133D01*
X793612Y-311200D01*
X793512Y-312400D01*
X793612Y-313600D01*
X793912Y-314667D01*
X794312Y-315467D01*
X794912Y-316133D01*
X795712Y-316400D01*
X796512Y-316133D01*
X797112Y-315467D01*
X797512Y-314667D01*
X797812Y-313600D01*
X797912Y-312400D01*
X797812Y-311200D01*
X797512Y-310133D01*
X797112Y-309333D01*
X796512Y-308667D01*
X795712Y-308400D01*
G01X803712D02*
Y-316400D01*
G01X801412Y-308400D02*
X806012D01*
G01X809812Y-313067D02*
X810512Y-312133D01*
X811112Y-311600D01*
X811912Y-311333D01*
X812612Y-311600D01*
X813112Y-312133D01*
X813512Y-312933D01*
X813612Y-313867D01*
X813512Y-314667D01*
X813112Y-315467D01*
X812512Y-316133D01*
X811812Y-316400D01*
X811012Y-316133D01*
X810312Y-315334D01*
X809912Y-314133D01*
X809812Y-312800D01*
X810012Y-311067D01*
X810312Y-310133D01*
X810812Y-309200D01*
X811512Y-308533D01*
X812212Y-308400D01*
X812912Y-308667D01*
X813412Y-309333D01*
G01X817112Y-316400D02*
Y-308400D01*
X819712Y-315067D01*
X822312Y-308400D01*
Y-316400D01*
G01X827712Y-308400D02*
Y-316400D01*
G01X825412Y-308400D02*
X830012D01*
G01X833612Y-316400D02*
Y-308400D01*
G01X837812D02*
Y-316400D01*
G01Y-312400D02*
X833612D01*
G01X843712Y-316400D02*
X844412Y-316267D01*
X845212Y-315867D01*
X845712Y-315200D01*
X845912Y-314267D01*
X845712Y-313334D01*
X845112Y-312533D01*
X844212Y-312133D01*
X843212D01*
X842612Y-311867D01*
X842112Y-311200D01*
X841912Y-310267D01*
X842212Y-309333D01*
X842912Y-308667D01*
X843712Y-308400D01*
X844512Y-308667D01*
X845212Y-309333D01*
X845512Y-310267D01*
X845312Y-311200D01*
X844812Y-311867D01*
X844212Y-312133D01*
X843212D01*
X842312Y-312533D01*
X841712Y-313334D01*
X841512Y-314267D01*
X841712Y-315200D01*
X842212Y-315867D01*
X843012Y-316267D01*
X843712Y-316400D01*
G01X853912Y-309067D02*
X853312Y-308667D01*
X852612Y-308400D01*
X851812D01*
X850912Y-308800D01*
X850212Y-309467D01*
X849712Y-310267D01*
X849312Y-311600D01*
X849212Y-312800D01*
X849412Y-314000D01*
X849712Y-314800D01*
X850312Y-315600D01*
X851012Y-316133D01*
X851712Y-316400D01*
X852412D01*
X853112Y-316133D01*
X853712Y-315733D01*
X854212Y-315200D01*
G01X859712Y-308400D02*
X858912Y-308667D01*
X858312Y-309333D01*
X857912Y-310133D01*
X857612Y-311200D01*
X857512Y-312400D01*
X857612Y-313600D01*
X857912Y-314667D01*
X858312Y-315467D01*
X858912Y-316133D01*
X859712Y-316400D01*
X860512Y-316133D01*
X861112Y-315467D01*
X861512Y-314667D01*
X861812Y-313600D01*
X861912Y-312400D01*
X861812Y-311200D01*
X861512Y-310133D01*
X861112Y-309333D01*
X860512Y-308667D01*
X859712Y-308400D01*
G01X799712Y-283400D02*
Y-291400D01*
G01X797412Y-283400D02*
X802012D01*
G01X805812Y-288067D02*
X806512Y-287133D01*
X807112Y-286600D01*
X807912Y-286333D01*
X808612Y-286600D01*
X809112Y-287133D01*
X809512Y-287933D01*
X809612Y-288867D01*
X809512Y-289667D01*
X809112Y-290467D01*
X808512Y-291133D01*
X807812Y-291400D01*
X807012Y-291133D01*
X806312Y-290334D01*
X805912Y-289133D01*
X805812Y-287800D01*
X806012Y-286067D01*
X806312Y-285133D01*
X806812Y-284200D01*
X807512Y-283533D01*
X808212Y-283400D01*
X808912Y-283667D01*
X809412Y-284333D01*
G01X813112Y-291400D02*
Y-283400D01*
X815712Y-290067D01*
X818312Y-283400D01*
Y-291400D01*
G01X820712Y-294067D02*
X826712D01*
G01X831712Y-283400D02*
Y-291400D01*
G01X829412Y-283400D02*
X834012D01*
G01X838312Y-291400D02*
Y-286067D01*
G01Y-287133D02*
X838812Y-286600D01*
X839312Y-286200D01*
X840012Y-286067D01*
X840512Y-286200D01*
X841112Y-286600D01*
G01X849512Y-291400D02*
Y-286067D01*
G01Y-287000D02*
X849112Y-286467D01*
X848512Y-286200D01*
X847812Y-286067D01*
X847112Y-286333D01*
X846512Y-286867D01*
X846112Y-287667D01*
X845912Y-288733D01*
X846112Y-289800D01*
X846512Y-290600D01*
X847112Y-291133D01*
X847812Y-291400D01*
X848512Y-291267D01*
X849112Y-290867D01*
X849512Y-290334D01*
G01X853612Y-293800D02*
X854212Y-294067D01*
X855012Y-293800D01*
X855512Y-293267D01*
X855912Y-292600D01*
X856512Y-290467D01*
X857812Y-286067D01*
G01X854612D02*
X856512Y-290467D01*
G01X860712Y-294067D02*
X866712D01*
G01X872512Y-287133D02*
X872912Y-286733D01*
X873212Y-286067D01*
X873412Y-285133D01*
X873212Y-284333D01*
X872812Y-283800D01*
X872112Y-283400D01*
X869412D01*
Y-291400D01*
X872712D01*
X873412Y-290867D01*
X873812Y-290067D01*
X874012Y-289133D01*
X873812Y-288200D01*
X873212Y-287400D01*
X872512Y-287133D01*
X869412D01*
G01X877712Y-291400D02*
Y-283400D01*
X880112D01*
X880912Y-283800D01*
X881512Y-284733D01*
X881712Y-285800D01*
X881512Y-286867D01*
X881012Y-287667D01*
X880112Y-288067D01*
X877712D01*
G01X896912Y-334067D02*
X896312Y-333667D01*
X895612Y-333400D01*
X894812D01*
X893912Y-333800D01*
X893212Y-334467D01*
X892712Y-335267D01*
X892312Y-336600D01*
X892212Y-337800D01*
X892412Y-339000D01*
X892712Y-339800D01*
X893312Y-340600D01*
X894012Y-341133D01*
X894712Y-341400D01*
X895412D01*
X896112Y-341133D01*
X896712Y-340733D01*
X897212Y-340200D01*
G01X922212Y-341400D02*
Y-333400D01*
X921012Y-335000D01*
G01Y-341400D02*
X923412D01*
G01X928312Y-338067D02*
X929012Y-337133D01*
X929612Y-336600D01*
X930412Y-336333D01*
X931112Y-336600D01*
X931612Y-337133D01*
X932012Y-337933D01*
X932112Y-338867D01*
X932012Y-339667D01*
X931612Y-340467D01*
X931012Y-341133D01*
X930312Y-341400D01*
X929512Y-341133D01*
X928812Y-340334D01*
X928412Y-339133D01*
X928312Y-337800D01*
X928512Y-336067D01*
X928812Y-335133D01*
X929312Y-334200D01*
X930012Y-333533D01*
X930712Y-333400D01*
X931412Y-333667D01*
X931912Y-334333D01*
M02*
